G04 ================== begin FILE IDENTIFICATION RECORD ==================*
G04 Layout Name:  13948-1b.brd*
G04 Film Name:    DRILL*
G04 File Format:  Gerber RS274X*
G04 File Origin:  Cadence Allegro 16.5-S045*
G04 Origin Date:  Thu Nov 13 15:45:53 2014*
G04 *
G04 Layer:  MANUFACTURING/NCLEGEND-1-8*
G04 Layer:  MANUFACTURING/DRILL SIZE*
G04 Layer:  DRAWING FORMAT/LAYER_PCB_STORY*
G04 Layer:  DRAWING FORMAT/LAYER_DRILL*
G04 Layer:  BOARD GEOMETRY/PANEL_OUTLINE*
G04 *
G04 Offset:    (0.00 0.00)*
G04 Mirror:    No*
G04 Mode:      Positive*
G04 Rotation:  0*
G04 FullContactRelief:  No*
G04 UndefLineWidth:     6.00*
G04 ================== end FILE IDENTIFICATION RECORD ====================*
%FSLAX35Y35*MOIN*%
%IR0*IPPOS*OFA0.00000B0.00000*MIA0B0*SFA1.00000B1.00000*%
%AMMACRO16*
1,1,.006,.005,0.0*
20,1,.006,.005,0.0,-.005,0.0,0.0*
1,1,.006,-.005,0.0*
1,1,.006,0.0,.005*
20,1,.006,0.0,.005,0.0,-.005,0.0*
1,1,.006,0.0,-.005*
1,1,.006,.0025,0.0*
20,1,.006,.0025,0.0,.0025,.005,0.0*
1,1,.006,.0025,.005*
20,1,.006,.0025,.005,.0015,.004,0.0*
1,1,.006,.0015,.004*
1,1,.006,.0015,0.0*
20,1,.006,.0015,0.0,.0035,0.0,0.0*
1,1,.006,.0035,0.0*
%
%ADD16MACRO16*%
%AMMACRO13*
1,1,.006,.006,.006*
20,1,.006,.006,.006,.006,-.006,0.0*
1,1,.006,.006,-.006*
20,1,.006,.006,-.006,-.006,-.006,0.0*
1,1,.006,-.006,-.006*
20,1,.006,-.006,-.006,-.006,.006,0.0*
1,1,.006,-.006,.006*
20,1,.006,-.006,.006,.006,.006,0.0*
1,1,.006,.006,.006*
1,1,.006,-.0019,.002*
20,1,.006,-.0019,.002,-.0013,.0026,0.0*
1,1,.006,-.0013,.0026*
20,1,.006,-.0013,.0026,-.0006,.0029,0.0*
1,1,.006,-.0006,.0029*
20,1,.006,-.0006,.0029,.0002,.003,0.0*
1,1,.006,.0002,.003*
20,1,.006,.0002,.003,.0012,.0028,0.0*
1,1,.006,.0012,.0028*
20,1,.006,.0012,.0028,.0019,.0023,0.0*
1,1,.006,.0019,.0023*
20,1,.006,.0019,.0023,.0021,.0017,0.0*
1,1,.006,.0021,.0017*
20,1,.006,.0021,.0017,.002,.0011,0.0*
1,1,.006,.002,.0011*
20,1,.006,.002,.0011,.0016,.0006,0.0*
1,1,.006,.0016,.0006*
20,1,.006,.0016,.0006,-.0004,-.0004,0.0*
1,1,.006,-.0004,-.0004*
20,1,.006,-.0004,-.0004,-.0013,-.0011,0.0*
1,1,.006,-.0013,-.0011*
20,1,.006,-.0013,-.0011,-.0019,-.0021,0.0*
1,1,.006,-.0019,-.0021*
20,1,.006,-.0019,-.0021,-.0021,-.003,0.0*
1,1,.006,-.0021,-.003*
20,1,.006,-.0021,-.003,.0021,-.003,0.0*
1,1,.006,.0021,-.003*
%
%ADD13MACRO13*%
%AMMACRO23*
1,1,.006,.00642,-.0155*
20,1,.006,.00642,-.0155,-.00642,-.0155,0.0*
1,1,.006,-.00642,-.0155*
20,1,.006,-.00642,-.0155,-.0155,-.00642,0.0*
1,1,.006,-.0155,-.00642*
20,1,.006,-.0155,-.00642,-.0155,.00642,0.0*
1,1,.006,-.0155,.00642*
20,1,.006,-.0155,.00642,-.00642,.0155,0.0*
1,1,.006,-.00642,.0155*
20,1,.006,-.00642,.0155,.00642,.0155,0.0*
1,1,.006,.00642,.0155*
20,1,.006,.00642,.0155,.0155,.00642,0.0*
1,1,.006,.0155,.00642*
20,1,.006,.0155,.00642,.0155,-.00642,0.0*
1,1,.006,.0155,-.00642*
20,1,.006,.0155,-.00642,.00642,-.0155,0.0*
1,1,.006,.00642,-.0155*
1,1,.006,-.00568,-.00543*
20,1,.006,-.00568,-.00543,-.00413,-.00672,0.0*
1,1,.006,-.00413,-.00672*
20,1,.006,-.00413,-.00672,-.00233,-.00749,0.0*
1,1,.006,-.00233,-.00749*
20,1,.006,-.00233,-.00749,0.0,-.00775,0.0*
1,1,.006,0.0,-.00775*
20,1,.006,0.0,-.00775,.00233,-.00723,0.0*
1,1,.006,.00233,-.00723*
20,1,.006,.00233,-.00723,.00413,-.0062,0.0*
1,1,.006,.00413,-.0062*
20,1,.006,.00413,-.0062,.00543,-.00439,0.0*
1,1,.006,.00543,-.00439*
20,1,.006,.00543,-.00439,.00568,-.00233,0.0*
1,1,.006,.00568,-.00233*
20,1,.006,.00568,-.00233,.00517,-.00026,0.0*
1,1,.006,.00517,-.00026*
20,1,.006,.00517,-.00026,.00387,.00103,0.0*
1,1,.006,.00387,.00103*
20,1,.006,.00387,.00103,.00207,.00207,0.0*
1,1,.006,.00207,.00207*
20,1,.006,.00207,.00207,.00026,.00232,0.0*
1,1,.006,.00026,.00232*
20,1,.006,.00026,.00232,-.00155,.00207,0.0*
1,1,.006,-.00155,.00207*
20,1,.006,-.00155,.00207,-.00387,.00103,0.0*
1,1,.006,-.00387,.00103*
20,1,.006,-.00387,.00103,-.0031,.00775,0.0*
1,1,.006,-.0031,.00775*
20,1,.006,-.0031,.00775,.00387,.00775,0.0*
1,1,.006,.00387,.00775*
%
%ADD23MACRO23*%
%AMMACRO18*
1,1,.006,.016,0.0*
20,1,.006,.016,0.0,0.0,-.016,0.0*
1,1,.006,0.0,-.016*
20,1,.006,0.0,-.016,-.016,0.0,0.0*
1,1,.006,-.016,0.0*
20,1,.006,-.016,0.0,0.0,.016,0.0*
1,1,.006,0.0,.016*
20,1,.006,0.0,.016,.016,0.0,0.0*
1,1,.006,.016,0.0*
1,1,.006,-.00507,-.00133*
20,1,.006,-.00507,-.00133,-.0032,.00053,0.0*
1,1,.006,-.0032,.00053*
20,1,.006,-.0032,.00053,-.0016,.0016,0.0*
1,1,.006,-.0016,.0016*
20,1,.006,-.0016,.0016,.00053,.00213,0.0*
1,1,.006,.00053,.00213*
20,1,.006,.00053,.00213,.0024,.0016,0.0*
1,1,.006,.0024,.0016*
20,1,.006,.0024,.0016,.00373,.00053,0.0*
1,1,.006,.00373,.00053*
20,1,.006,.00373,.00053,.0048,-.00107,0.0*
1,1,.006,.0048,-.00107*
20,1,.006,.0048,-.00107,.00507,-.00293,0.0*
1,1,.006,.00507,-.00293*
20,1,.006,.00507,-.00293,.0048,-.00453,0.0*
1,1,.006,.0048,-.00453*
20,1,.006,.0048,-.00453,.00373,-.00613,0.0*
1,1,.006,.00373,-.00613*
20,1,.006,.00373,-.00613,.00213,-.00747,0.0*
1,1,.006,.00213,-.00747*
20,1,.006,.00213,-.00747,.00027,-.008,0.0*
1,1,.006,.00027,-.008*
20,1,.006,.00027,-.008,-.00187,-.00747,0.0*
1,1,.006,-.00187,-.00747*
20,1,.006,-.00187,-.00747,-.00373,-.00587,0.0*
1,1,.006,-.00373,-.00587*
20,1,.006,-.00373,-.00587,-.0048,-.00347,0.0*
1,1,.006,-.0048,-.00347*
20,1,.006,-.0048,-.00347,-.00507,-.0008,0.0*
1,1,.006,-.00507,-.0008*
20,1,.006,-.00507,-.0008,-.00453,.00267,0.0*
1,1,.006,-.00453,.00267*
20,1,.006,-.00453,.00267,-.00373,.00453,0.0*
1,1,.006,-.00373,.00453*
20,1,.006,-.00373,.00453,-.0024,.0064,0.0*
1,1,.006,-.0024,.0064*
20,1,.006,-.0024,.0064,-.00053,.00773,0.0*
1,1,.006,-.00053,.00773*
20,1,.006,-.00053,.00773,.00133,.008,0.0*
1,1,.006,.00133,.008*
20,1,.006,.00133,.008,.0032,.00747,0.0*
1,1,.006,.0032,.00747*
20,1,.006,.0032,.00747,.00453,.00613,0.0*
1,1,.006,.00453,.00613*
%
%ADD18MACRO18*%
%AMMACRO26*
1,1,.006,.00667,.00167*
20,1,.006,.00667,.00167,.01,.00417,0.0*
1,1,.006,.01,.00417*
20,1,.006,.01,.00417,.0125,.00833,0.0*
1,1,.006,.0125,.00833*
20,1,.006,.0125,.00833,.01417,.01417,0.0*
1,1,.006,.01417,.01417*
20,1,.006,.01417,.01417,.0125,.01917,0.0*
1,1,.006,.0125,.01917*
20,1,.006,.0125,.01917,.00917,.0225,0.0*
1,1,.006,.00917,.0225*
20,1,.006,.00917,.0225,.00333,.025,0.0*
1,1,.006,.00333,.025*
20,1,.006,.00333,.025,-.01917,.025,0.0*
1,1,.006,-.01917,.025*
20,1,.006,-.01917,.025,-.01917,-.025,0.0*
1,1,.006,-.01917,-.025*
20,1,.006,-.01917,-.025,.00833,-.025,0.0*
1,1,.006,.00833,-.025*
20,1,.006,.00833,-.025,.01417,-.02167,0.0*
1,1,.006,.01417,-.02167*
20,1,.006,.01417,-.02167,.0175,-.01667,0.0*
1,1,.006,.0175,-.01667*
20,1,.006,.0175,-.01667,.01917,-.01083,0.0*
1,1,.006,.01917,-.01083*
20,1,.006,.01917,-.01083,.0175,-.005,0.0*
1,1,.006,.0175,-.005*
20,1,.006,.0175,-.005,.0125,0.0,0.0*
1,1,.006,.0125,0.0*
20,1,.006,.0125,0.0,.00667,.00167,0.0*
1,1,.006,.00667,.00167*
20,1,.006,.00667,.00167,-.01917,.00167,0.0*
1,1,.006,-.01917,.00167*
%
%ADD26MACRO26*%
%AMMACRO38*
1,1,.006,-.01013,-.016*
20,1,.006,-.01013,-.016,-.01013,.016,0.0*
1,1,.006,-.01013,.016*
20,1,.006,-.01013,.016,.01013,.016,0.0*
1,1,.006,.01013,.016*
1,1,.006,.00267,.00053*
20,1,.006,.00267,.00053,-.01013,.00053,0.0*
1,1,.006,-.01013,.00053*
%
%ADD38MACRO38*%
%AMMACRO30*
1,1,.006,-.008,.02*
20,1,.006,-.008,.02,.008,.02,0.0*
1,1,.006,.008,.02*
1,1,.006,0.0,.02*
20,1,.006,0.0,.02,0.0,-.02,0.0*
1,1,.006,0.0,-.02*
1,1,.006,-.008,-.02*
20,1,.006,-.008,-.02,.008,-.02,0.0*
1,1,.006,.008,-.02*
%
%ADD30MACRO30*%
%AMMACRO27*
1,1,.006,.02273,.02583*
20,1,.006,.02273,.02583,.01653,.02893,0.0*
1,1,.006,.01653,.02893*
20,1,.006,.01653,.02893,.0093,.031,0.0*
1,1,.006,.0093,.031*
20,1,.006,.0093,.031,.00103,.031,0.0*
1,1,.006,.00103,.031*
20,1,.006,.00103,.031,-.00827,.0279,0.0*
1,1,.006,-.00827,.0279*
20,1,.006,-.00827,.0279,-.0155,.02273,0.0*
1,1,.006,-.0155,.02273*
20,1,.006,-.0155,.02273,-.02067,.01653,0.0*
1,1,.006,-.02067,.01653*
20,1,.006,-.02067,.01653,-.0248,.0062,0.0*
1,1,.006,-.0248,.0062*
20,1,.006,-.0248,.0062,-.02583,-.0031,0.0*
1,1,.006,-.02583,-.0031*
20,1,.006,-.02583,-.0031,-.02377,-.0124,0.0*
1,1,.006,-.02377,-.0124*
20,1,.006,-.02377,-.0124,-.02067,-.0186,0.0*
1,1,.006,-.02067,-.0186*
20,1,.006,-.02067,-.0186,-.01447,-.0248,0.0*
1,1,.006,-.01447,-.0248*
20,1,.006,-.01447,-.0248,-.00723,-.02893,0.0*
1,1,.006,-.00723,-.02893*
20,1,.006,-.00723,-.02893,0.0,-.031,0.0*
1,1,.006,0.0,-.031*
20,1,.006,0.0,-.031,.00723,-.031,0.0*
1,1,.006,.00723,-.031*
20,1,.006,.00723,-.031,.01447,-.02893,0.0*
1,1,.006,.01447,-.02893*
20,1,.006,.01447,-.02893,.02067,-.02583,0.0*
1,1,.006,.02067,-.02583*
20,1,.006,.02067,-.02583,.02583,-.0217,0.0*
1,1,.006,.02583,-.0217*
%
%ADD27MACRO27*%
%AMMACRO19*
1,1,.006,-.01875,-.0225*
20,1,.006,-.01875,-.0225,0.0,.0225,0.0*
1,1,.006,0.0,.0225*
20,1,.006,0.0,.0225,.01875,-.0225,0.0*
1,1,.006,.01875,-.0225*
1,1,.006,.012,-.00675*
20,1,.006,.012,-.00675,-.012,-.00675,0.0*
1,1,.006,-.012,-.00675*
%
%ADD19MACRO19*%
%AMMACRO35*
1,1,.006,.0034,0.0*
20,1,.006,.0034,0.0,.01473,0.0,0.0*
1,1,.006,.01473,0.0*
20,1,.006,.01473,0.0,.01473,-.0102,0.0*
1,1,.006,.01473,-.0102*
20,1,.006,.01473,-.0102,.01133,-.0136,0.0*
1,1,.006,.01133,-.0136*
20,1,.006,.01133,-.0136,.00737,-.01587,0.0*
1,1,.006,.00737,-.01587*
20,1,.006,.00737,-.01587,.0017,-.017,0.0*
1,1,.006,.0017,-.017*
20,1,.006,.0017,-.017,-.00397,-.01587,0.0*
1,1,.006,-.00397,-.01587*
20,1,.006,-.00397,-.01587,-.00793,-.0136,0.0*
1,1,.006,-.00793,-.0136*
20,1,.006,-.00793,-.0136,-.01133,-.0102,0.0*
1,1,.006,-.01133,-.0102*
20,1,.006,-.01133,-.0102,-.0136,-.00623,0.0*
1,1,.006,-.0136,-.00623*
20,1,.006,-.0136,-.00623,-.01473,-.0017,0.0*
1,1,.006,-.01473,-.0017*
20,1,.006,-.01473,-.0017,-.01473,.00227,0.0*
1,1,.006,-.01473,.00227*
20,1,.006,-.01473,.00227,-.0136,.00567,0.0*
1,1,.006,-.0136,.00567*
20,1,.006,-.0136,.00567,-.01133,.00963,0.0*
1,1,.006,-.01133,.00963*
20,1,.006,-.01133,.00963,-.00793,.01303,0.0*
1,1,.006,-.00793,.01303*
20,1,.006,-.00793,.01303,-.00453,.0153,0.0*
1,1,.006,-.00453,.0153*
20,1,.006,-.00453,.0153,0.0,.017,0.0*
1,1,.006,0.0,.017*
20,1,.006,0.0,.017,.00397,.017,0.0*
1,1,.006,.00397,.017*
20,1,.006,.00397,.017,.0085,.01587,0.0*
1,1,.006,.0085,.01587*
20,1,.006,.0085,.01587,.0119,.0136,0.0*
1,1,.006,.0119,.0136*
%
%ADD35MACRO35*%
%AMMACRO32*
1,1,.006,-.03337,-.0455*
20,1,.006,-.03337,-.0455,-.03337,.0455,0.0*
1,1,.006,-.03337,.0455*
20,1,.006,-.03337,.0455,-.00303,.0455,0.0*
1,1,.006,-.00303,.0455*
20,1,.006,-.00303,.0455,.0091,.04095,0.0*
1,1,.006,.0091,.04095*
20,1,.006,.0091,.04095,.0182,.03488,0.0*
1,1,.006,.0182,.03488*
20,1,.006,.0182,.03488,.02578,.02578,0.0*
1,1,.006,.02578,.02578*
20,1,.006,.02578,.02578,.03185,.01516,0.0*
1,1,.006,.03185,.01516*
20,1,.006,.03185,.01516,.03337,0.0,0.0*
1,1,.006,.03337,0.0*
20,1,.006,.03337,0.0,.03185,-.01517,0.0*
1,1,.006,.03185,-.01517*
20,1,.006,.03185,-.01517,.02578,-.02578,0.0*
1,1,.006,.02578,-.02578*
20,1,.006,.02578,-.02578,.0182,-.03489,0.0*
1,1,.006,.0182,-.03489*
20,1,.006,.0182,-.03489,.0091,-.04095,0.0*
1,1,.006,.0091,-.04095*
20,1,.006,.0091,-.04095,-.00303,-.0455,0.0*
1,1,.006,-.00303,-.0455*
20,1,.006,-.00303,-.0455,-.03337,-.0455,0.0*
1,1,.006,-.03337,-.0455*
%
%ADD32MACRO32*%
%AMMACRO15*
1,1,.006,-.02237,-.0305*
20,1,.006,-.02237,-.0305,-.02237,.0305,0.0*
1,1,.006,-.02237,.0305*
1,1,.006,.01627,.0305*
20,1,.006,.01627,.0305,-.02237,-.00712,0.0*
1,1,.006,-.02237,-.00712*
1,1,.006,.02237,-.0305*
20,1,.006,.02237,-.0305,-.00508,.01017,0.0*
1,1,.006,-.00508,.01017*
%
%ADD15MACRO15*%
%AMMACRO21*
1,1,.006,0.0,-.063*
20,1,.006,0.0,-.063,-.0168,-.0609,0.0*
1,1,.006,-.0168,-.0609*
20,1,.006,-.0168,-.0609,-.0315,-.0525,0.0*
1,1,.006,-.0315,-.0525*
20,1,.006,-.0315,-.0525,-.0441,-.0399,0.0*
1,1,.006,-.0441,-.0399*
20,1,.006,-.0441,-.0399,-.0525,-.0252,0.0*
1,1,.006,-.0525,-.0252*
20,1,.006,-.0525,-.0252,-.0567,-.0084,0.0*
1,1,.006,-.0567,-.0084*
20,1,.006,-.0567,-.0084,-.0567,.0084,0.0*
1,1,.006,-.0567,.0084*
20,1,.006,-.0567,.0084,-.0525,.0252,0.0*
1,1,.006,-.0525,.0252*
20,1,.006,-.0525,.0252,-.0441,.0399,0.0*
1,1,.006,-.0441,.0399*
20,1,.006,-.0441,.0399,-.0315,.0525,0.0*
1,1,.006,-.0315,.0525*
20,1,.006,-.0315,.0525,-.0168,.0609,0.0*
1,1,.006,-.0168,.0609*
20,1,.006,-.0168,.0609,0.0,.063,0.0*
1,1,.006,0.0,.063*
20,1,.006,0.0,.063,.0168,.0609,0.0*
1,1,.006,.0168,.0609*
20,1,.006,.0168,.0609,.0315,.0525,0.0*
1,1,.006,.0315,.0525*
20,1,.006,.0315,.0525,.0441,.0399,0.0*
1,1,.006,.0441,.0399*
20,1,.006,.0441,.0399,.0525,.0252,0.0*
1,1,.006,.0525,.0252*
20,1,.006,.0525,.0252,.0567,.0084,0.0*
1,1,.006,.0567,.0084*
20,1,.006,.0567,.0084,.0567,-.0084,0.0*
1,1,.006,.0567,-.0084*
20,1,.006,.0567,-.0084,.0525,-.0252,0.0*
1,1,.006,.0525,-.0252*
20,1,.006,.0525,-.0252,.0441,-.0399,0.0*
1,1,.006,.0441,-.0399*
20,1,.006,.0441,-.0399,.0315,-.0525,0.0*
1,1,.006,.0315,-.0525*
20,1,.006,.0315,-.0525,.0168,-.0609,0.0*
1,1,.006,.0168,-.0609*
20,1,.006,.0168,-.0609,0.0,-.063,0.0*
1,1,.006,0.0,-.063*
%
%ADD21MACRO21*%
%AMMACRO12*
1,1,.006,-.02067,.031*
20,1,.006,-.02067,.031,-.02067,-.031,0.0*
1,1,.006,-.02067,-.031*
20,1,.006,-.02067,-.031,.02067,-.031,0.0*
1,1,.006,.02067,-.031*
%
%ADD12MACRO12*%
%AMMACRO37*
1,1,.006,-.0133,-.019*
20,1,.006,-.0133,-.019,-.0133,.019,0.0*
1,1,.006,-.0133,.019*
1,1,.006,.0133,.019*
20,1,.006,.0133,.019,.0133,-.019,0.0*
1,1,.006,.0133,-.019*
1,1,.006,.0133,0.0*
20,1,.006,.0133,0.0,-.0133,0.0,0.0*
1,1,.006,-.0133,0.0*
%
%ADD37MACRO37*%
%AMMACRO28*
1,1,.006,-.04267,-.064*
20,1,.006,-.04267,-.064,-.04267,.064,0.0*
1,1,.006,-.04267,.064*
20,1,.006,-.04267,.064,.00853,.064,0.0*
1,1,.006,.00853,.064*
20,1,.006,.00853,.064,.0256,.0576,0.0*
1,1,.006,.0256,.0576*
20,1,.006,.0256,.0576,.0384,.04267,0.0*
1,1,.006,.0384,.04267*
20,1,.006,.0384,.04267,.04267,.0256,0.0*
1,1,.006,.04267,.0256*
20,1,.006,.04267,.0256,.0384,.00853,0.0*
1,1,.006,.0384,.00853*
20,1,.006,.0384,.00853,.02773,-.00427,0.0*
1,1,.006,.02773,-.00427*
20,1,.006,.02773,-.00427,.00853,-.01067,0.0*
1,1,.006,.00853,-.01067*
20,1,.006,.00853,-.01067,-.04267,-.01067,0.0*
1,1,.006,-.04267,-.01067*
%
%ADD28MACRO28*%
%AMMACRO34*
1,1,.006,-.016,-.0144*
20,1,.006,-.016,-.0144,-.012,-.0192,0.0*
1,1,.006,-.012,-.0192*
20,1,.006,-.012,-.0192,-.0072,-.0224,0.0*
1,1,.006,-.0072,-.0224*
20,1,.006,-.0072,-.0224,-.0016,-.024,0.0*
1,1,.006,-.0016,-.024*
20,1,.006,-.0016,-.024,.0048,-.0224,0.0*
1,1,.006,.0048,-.0224*
20,1,.006,.0048,-.0224,.0096,-.0192,0.0*
1,1,.006,.0096,-.0192*
20,1,.006,.0096,-.0192,.0144,-.0144,0.0*
1,1,.006,.0144,-.0144*
20,1,.006,.0144,-.0144,.016,-.008,0.0*
1,1,.006,.016,-.008*
20,1,.006,.016,-.008,.016,.024,0.0*
1,1,.006,.016,.024*
%
%ADD34MACRO34*%
%AMMACRO22*
1,1,.006,0.0,-.069*
20,1,.006,0.0,-.069,-.0184,-.0667,0.0*
1,1,.006,-.0184,-.0667*
20,1,.006,-.0184,-.0667,-.0345,-.0575,0.0*
1,1,.006,-.0345,-.0575*
20,1,.006,-.0345,-.0575,-.0483,-.0437,0.0*
1,1,.006,-.0483,-.0437*
20,1,.006,-.0483,-.0437,-.0575,-.0276,0.0*
1,1,.006,-.0575,-.0276*
20,1,.006,-.0575,-.0276,-.0621,-.0092,0.0*
1,1,.006,-.0621,-.0092*
20,1,.006,-.0621,-.0092,-.0621,.0092,0.0*
1,1,.006,-.0621,.0092*
20,1,.006,-.0621,.0092,-.0575,.0276,0.0*
1,1,.006,-.0575,.0276*
20,1,.006,-.0575,.0276,-.0483,.0437,0.0*
1,1,.006,-.0483,.0437*
20,1,.006,-.0483,.0437,-.0345,.0575,0.0*
1,1,.006,-.0345,.0575*
20,1,.006,-.0345,.0575,-.0184,.0667,0.0*
1,1,.006,-.0184,.0667*
20,1,.006,-.0184,.0667,0.0,.069,0.0*
1,1,.006,0.0,.069*
20,1,.006,0.0,.069,.0184,.0667,0.0*
1,1,.006,.0184,.0667*
20,1,.006,.0184,.0667,.0345,.0575,0.0*
1,1,.006,.0345,.0575*
20,1,.006,.0345,.0575,.0483,.0437,0.0*
1,1,.006,.0483,.0437*
20,1,.006,.0483,.0437,.0575,.0276,0.0*
1,1,.006,.0575,.0276*
20,1,.006,.0575,.0276,.0621,.0092,0.0*
1,1,.006,.0621,.0092*
20,1,.006,.0621,.0092,.0621,-.0092,0.0*
1,1,.006,.0621,-.0092*
20,1,.006,.0621,-.0092,.0575,-.0276,0.0*
1,1,.006,.0575,-.0276*
20,1,.006,.0575,-.0276,.0483,-.0437,0.0*
1,1,.006,.0483,-.0437*
20,1,.006,.0483,-.0437,.0345,-.0575,0.0*
1,1,.006,.0345,-.0575*
20,1,.006,.0345,-.0575,.0184,-.0667,0.0*
1,1,.006,.0184,-.0667*
20,1,.006,.0184,-.0667,0.0,-.069,0.0*
1,1,.006,0.0,-.069*
1,1,.006,.0184,-.0322*
20,1,.006,.0184,-.0322,.046,-.069,0.0*
1,1,.006,.046,-.069*
%
%ADD22MACRO22*%
%AMMACRO24*
1,1,.006,-.03565,-.0465*
20,1,.006,-.03565,-.0465,-.03565,.0465,0.0*
1,1,.006,-.03565,.0465*
20,1,.006,-.03565,.0465,.03565,-.0465,0.0*
1,1,.006,.03565,-.0465*
20,1,.006,.03565,-.0465,.03565,.0465,0.0*
1,1,.006,.03565,.0465*
%
%ADD24MACRO24*%
%AMMACRO14*
1,1,.006,-.03727,-.043*
20,1,.006,-.03727,-.043,-.03727,.043,0.0*
1,1,.006,-.03727,.043*
20,1,.006,-.03727,.043,0.0,-.02867,0.0*
1,1,.006,0.0,-.02867*
20,1,.006,0.0,-.02867,.03727,.043,0.0*
1,1,.006,.03727,.043*
20,1,.006,.03727,.043,.03727,-.043,0.0*
1,1,.006,.03727,-.043*
%
%ADD14MACRO14*%
%AMMACRO11*
1,1,.006,.033,-.0495*
20,1,.006,.033,-.0495,-.033,-.0495,0.0*
1,1,.006,-.033,-.0495*
20,1,.006,-.033,-.0495,-.033,.0495,0.0*
1,1,.006,-.033,.0495*
20,1,.006,-.033,.0495,.033,.0495,0.0*
1,1,.006,.033,.0495*
1,1,.006,.0066,.00165*
20,1,.006,.0066,.00165,-.033,.00165,0.0*
1,1,.006,-.033,.00165*
%
%ADD11MACRO11*%
%AMMACRO20*
1,1,.006,.02,.015*
20,1,.006,.02,.015,.02,-.015,0.0*
1,1,.006,.02,-.015*
20,1,.006,.02,-.015,-.02,-.015,0.0*
1,1,.006,-.02,-.015*
20,1,.006,-.02,-.015,-.02,.015,0.0*
1,1,.006,-.02,.015*
20,1,.006,-.02,.015,.02,.015,0.0*
1,1,.006,.02,.015*
1,1,.006,-.0075,-.0075*
20,1,.006,-.0075,-.0075,-.0075,.0075,0.0*
1,1,.006,-.0075,.0075*
20,1,.006,-.0075,.0075,-.0105,.0045,0.0*
1,1,.006,-.0105,.0045*
1,1,.006,-.0105,-.0075*
20,1,.006,-.0105,-.0075,-.0045,-.0075,0.0*
1,1,.006,-.0045,-.0075*
1,1,.006,.00751,.0075*
20,1,.006,.00751,.0075,.00551,.007,0.0*
1,1,.006,.00551,.007*
20,1,.006,.00551,.007,.00401,.00575,0.0*
1,1,.006,.00401,.00575*
20,1,.006,.00401,.00575,.00301,.00425,0.0*
1,1,.006,.00301,.00425*
20,1,.006,.00301,.00425,.00226,.00225,0.0*
1,1,.006,.00226,.00225*
20,1,.006,.00226,.00225,.00201,0.0,0.0*
1,1,.006,.00201,0.0*
20,1,.006,.00201,0.0,.00226,-.00225,0.0*
1,1,.006,.00226,-.00225*
20,1,.006,.00226,-.00225,.00301,-.00425,0.0*
1,1,.006,.00301,-.00425*
20,1,.006,.00301,-.00425,.00401,-.00575,0.0*
1,1,.006,.00401,-.00575*
20,1,.006,.00401,-.00575,.00551,-.007,0.0*
1,1,.006,.00551,-.007*
20,1,.006,.00551,-.007,.00751,-.0075,0.0*
1,1,.006,.00751,-.0075*
20,1,.006,.00751,-.0075,.00951,-.007,0.0*
1,1,.006,.00951,-.007*
20,1,.006,.00951,-.007,.01101,-.00575,0.0*
1,1,.006,.01101,-.00575*
20,1,.006,.01101,-.00575,.01201,-.00425,0.0*
1,1,.006,.01201,-.00425*
20,1,.006,.01201,-.00425,.01276,-.00225,0.0*
1,1,.006,.01276,-.00225*
20,1,.006,.01276,-.00225,.01301,0.0,0.0*
1,1,.006,.01301,0.0*
20,1,.006,.01301,0.0,.01276,.00225,0.0*
1,1,.006,.01276,.00225*
20,1,.006,.01276,.00225,.01201,.00425,0.0*
1,1,.006,.01201,.00425*
20,1,.006,.01201,.00425,.01101,.00575,0.0*
1,1,.006,.01101,.00575*
20,1,.006,.01101,.00575,.00951,.007,0.0*
1,1,.006,.00951,.007*
20,1,.006,.00951,.007,.00751,.0075,0.0*
1,1,.006,.00751,.0075*
%
%ADD20MACRO20*%
%AMMACRO36*
1,1,.006,.021,0.0*
20,1,.006,.021,0.0,.020681,-.003647,0.0*
1,1,.006,.020681,-.003647*
20,1,.006,.020681,-.003647,.019734,-.007182,0.0*
1,1,.006,.019734,-.007182*
20,1,.006,.019734,-.007182,.018187,-.0105,0.0*
1,1,.006,.018187,-.0105*
20,1,.006,.018187,-.0105,.016087,-.013499,0.0*
1,1,.006,.016087,-.013499*
20,1,.006,.016087,-.013499,.013499,-.016087,0.0*
1,1,.006,.013499,-.016087*
20,1,.006,.013499,-.016087,.0105,-.018187,0.0*
1,1,.006,.0105,-.018187*
20,1,.006,.0105,-.018187,.007182,-.019734,0.0*
1,1,.006,.007182,-.019734*
20,1,.006,.007182,-.019734,.003647,-.020681,0.0*
1,1,.006,.003647,-.020681*
20,1,.006,.003647,-.020681,0.0,-.021,0.0*
1,1,.006,0.0,-.021*
20,1,.006,0.0,-.021,-.003647,-.020681,0.0*
1,1,.006,-.003647,-.020681*
20,1,.006,-.003647,-.020681,-.007182,-.019734,0.0*
1,1,.006,-.007182,-.019734*
20,1,.006,-.007182,-.019734,-.0105,-.018187,0.0*
1,1,.006,-.0105,-.018187*
20,1,.006,-.0105,-.018187,-.013499,-.016087,0.0*
1,1,.006,-.013499,-.016087*
20,1,.006,-.013499,-.016087,-.016087,-.013499,0.0*
1,1,.006,-.016087,-.013499*
20,1,.006,-.016087,-.013499,-.018187,-.0105,0.0*
1,1,.006,-.018187,-.0105*
20,1,.006,-.018187,-.0105,-.019734,-.007182,0.0*
1,1,.006,-.019734,-.007182*
20,1,.006,-.019734,-.007182,-.020681,-.003647,0.0*
1,1,.006,-.020681,-.003647*
20,1,.006,-.020681,-.003647,-.021,0.0,0.0*
1,1,.006,-.021,0.0*
20,1,.006,-.021,0.0,-.020681,.003647,0.0*
1,1,.006,-.020681,.003647*
20,1,.006,-.020681,.003647,-.019734,.007182,0.0*
1,1,.006,-.019734,.007182*
20,1,.006,-.019734,.007182,-.018187,.0105,0.0*
1,1,.006,-.018187,.0105*
20,1,.006,-.018187,.0105,-.016087,.013499,0.0*
1,1,.006,-.016087,.013499*
20,1,.006,-.016087,.013499,-.013499,.016087,0.0*
1,1,.006,-.013499,.016087*
20,1,.006,-.013499,.016087,-.0105,.018187,0.0*
1,1,.006,-.0105,.018187*
20,1,.006,-.0105,.018187,-.007182,.019734,0.0*
1,1,.006,-.007182,.019734*
20,1,.006,-.007182,.019734,-.003647,.020681,0.0*
1,1,.006,-.003647,.020681*
20,1,.006,-.003647,.020681,0.0,.021,0.0*
1,1,.006,0.0,.021*
20,1,.006,0.0,.021,.003647,.020681,0.0*
1,1,.006,.003647,.020681*
20,1,.006,.003647,.020681,.007182,.019734,0.0*
1,1,.006,.007182,.019734*
20,1,.006,.007182,.019734,.0105,.018187,0.0*
1,1,.006,.0105,.018187*
20,1,.006,.0105,.018187,.013499,.016087,0.0*
1,1,.006,.013499,.016087*
20,1,.006,.013499,.016087,.016087,.013499,0.0*
1,1,.006,.016087,.013499*
20,1,.006,.016087,.013499,.018187,.0105,0.0*
1,1,.006,.018187,.0105*
20,1,.006,.018187,.0105,.019734,.007182,0.0*
1,1,.006,.019734,.007182*
20,1,.006,.019734,.007182,.020681,.003647,0.0*
1,1,.006,.020681,.003647*
20,1,.006,.020681,.003647,.021,0.0,0.0*
1,1,.006,.021,0.0*
1,1,.006,-.0105,-.0105*
20,1,.006,-.0105,-.0105,-.0105,.0105,0.0*
1,1,.006,-.0105,.0105*
20,1,.006,-.0105,.0105,-.0147,.0063,0.0*
1,1,.006,-.0147,.0063*
1,1,.006,-.0147,-.0105*
20,1,.006,-.0147,-.0105,-.0063,-.0105,0.0*
1,1,.006,-.0063,-.0105*
1,1,.006,.01051,-.0105*
20,1,.006,.01051,-.0105,.01051,.0105,0.0*
1,1,.006,.01051,.0105*
20,1,.006,.01051,.0105,.00631,.0063,0.0*
1,1,.006,.00631,.0063*
1,1,.006,.00631,-.0105*
20,1,.006,.00631,-.0105,.01471,-.0105,0.0*
1,1,.006,.01471,-.0105*
%
%ADD36MACRO36*%
%AMMACRO31*
1,1,.006,-.0315,.063*
20,1,.006,-.0315,.063,.0315,.063,0.0*
1,1,.006,.0315,.063*
20,1,.006,.0315,.063,.04244,.062043,0.0*
1,1,.006,.04244,.062043*
20,1,.006,.04244,.062043,.053047,.059201,0.0*
1,1,.006,.053047,.059201*
20,1,.006,.053047,.059201,.063,.05456,0.0*
1,1,.006,.063,.05456*
20,1,.006,.063,.05456,.071996,.048261,0.0*
1,1,.006,.071996,.048261*
20,1,.006,.071996,.048261,.079761,.040496,0.0*
1,1,.006,.079761,.040496*
20,1,.006,.079761,.040496,.08606,.0315,0.0*
1,1,.006,.08606,.0315*
20,1,.006,.08606,.0315,.090701,.021547,0.0*
1,1,.006,.090701,.021547*
20,1,.006,.090701,.021547,.093543,.01094,0.0*
1,1,.006,.093543,.01094*
20,1,.006,.093543,.01094,.0945,0.0,0.0*
1,1,.006,.0945,0.0*
20,1,.006,.0945,0.0,.093543,-.01094,0.0*
1,1,.006,.093543,-.01094*
20,1,.006,.093543,-.01094,.090701,-.021547,0.0*
1,1,.006,.090701,-.021547*
20,1,.006,.090701,-.021547,.08606,-.0315,0.0*
1,1,.006,.08606,-.0315*
20,1,.006,.08606,-.0315,.079761,-.040496,0.0*
1,1,.006,.079761,-.040496*
20,1,.006,.079761,-.040496,.071996,-.048261,0.0*
1,1,.006,.071996,-.048261*
20,1,.006,.071996,-.048261,.063,-.05456,0.0*
1,1,.006,.063,-.05456*
20,1,.006,.063,-.05456,.053047,-.059201,0.0*
1,1,.006,.053047,-.059201*
20,1,.006,.053047,-.059201,.04244,-.062043,0.0*
1,1,.006,.04244,-.062043*
20,1,.006,.04244,-.062043,.0315,-.063,0.0*
1,1,.006,.0315,-.063*
20,1,.006,.0315,-.063,-.0315,-.063,0.0*
1,1,.006,-.0315,-.063*
20,1,.006,-.0315,-.063,-.04244,-.062043,0.0*
1,1,.006,-.04244,-.062043*
20,1,.006,-.04244,-.062043,-.053047,-.059201,0.0*
1,1,.006,-.053047,-.059201*
20,1,.006,-.053047,-.059201,-.063,-.05456,0.0*
1,1,.006,-.063,-.05456*
20,1,.006,-.063,-.05456,-.071996,-.048261,0.0*
1,1,.006,-.071996,-.048261*
20,1,.006,-.071996,-.048261,-.079761,-.040496,0.0*
1,1,.006,-.079761,-.040496*
20,1,.006,-.079761,-.040496,-.08606,-.0315,0.0*
1,1,.006,-.08606,-.0315*
20,1,.006,-.08606,-.0315,-.090701,-.021547,0.0*
1,1,.006,-.090701,-.021547*
20,1,.006,-.090701,-.021547,-.093543,-.01094,0.0*
1,1,.006,-.093543,-.01094*
20,1,.006,-.093543,-.01094,-.0945,0.0,0.0*
1,1,.006,-.0945,0.0*
20,1,.006,-.0945,0.0,-.093543,.01094,0.0*
1,1,.006,-.093543,.01094*
20,1,.006,-.093543,.01094,-.090701,.021547,0.0*
1,1,.006,-.090701,.021547*
20,1,.006,-.090701,.021547,-.08606,.0315,0.0*
1,1,.006,-.08606,.0315*
20,1,.006,-.08606,.0315,-.079761,.040496,0.0*
1,1,.006,-.079761,.040496*
20,1,.006,-.079761,.040496,-.071996,.048261,0.0*
1,1,.006,-.071996,.048261*
20,1,.006,-.071996,.048261,-.063,.05456,0.0*
1,1,.006,-.063,.05456*
20,1,.006,-.063,.05456,-.053047,.059201,0.0*
1,1,.006,-.053047,.059201*
20,1,.006,-.053047,.059201,-.04244,.062043,0.0*
1,1,.006,-.04244,.062043*
20,1,.006,-.04244,.062043,-.0315,.063,0.0*
1,1,.006,-.0315,.063*
1,1,.006,-.0315,-.0315*
20,1,.006,-.0315,-.0315,-.0399,-.03045,0.0*
1,1,.006,-.0399,-.03045*
20,1,.006,-.0399,-.03045,-.04725,-.02625,0.0*
1,1,.006,-.04725,-.02625*
20,1,.006,-.04725,-.02625,-.05355,-.01995,0.0*
1,1,.006,-.05355,-.01995*
20,1,.006,-.05355,-.01995,-.05775,-.0126,0.0*
1,1,.006,-.05775,-.0126*
20,1,.006,-.05775,-.0126,-.05985,-.0042,0.0*
1,1,.006,-.05985,-.0042*
20,1,.006,-.05985,-.0042,-.05985,.0042,0.0*
1,1,.006,-.05985,.0042*
20,1,.006,-.05985,.0042,-.05775,.0126,0.0*
1,1,.006,-.05775,.0126*
20,1,.006,-.05775,.0126,-.05355,.01995,0.0*
1,1,.006,-.05355,.01995*
20,1,.006,-.05355,.01995,-.04725,.02625,0.0*
1,1,.006,-.04725,.02625*
20,1,.006,-.04725,.02625,-.0399,.03045,0.0*
1,1,.006,-.0399,.03045*
20,1,.006,-.0399,.03045,-.0315,.0315,0.0*
1,1,.006,-.0315,.0315*
20,1,.006,-.0315,.0315,-.0231,.03045,0.0*
1,1,.006,-.0231,.03045*
20,1,.006,-.0231,.03045,-.01575,.02625,0.0*
1,1,.006,-.01575,.02625*
20,1,.006,-.01575,.02625,-.00945,.01995,0.0*
1,1,.006,-.00945,.01995*
20,1,.006,-.00945,.01995,-.00525,.0126,0.0*
1,1,.006,-.00525,.0126*
20,1,.006,-.00525,.0126,-.00315,.0042,0.0*
1,1,.006,-.00315,.0042*
20,1,.006,-.00315,.0042,-.00315,-.0042,0.0*
1,1,.006,-.00315,-.0042*
20,1,.006,-.00315,-.0042,-.00525,-.0126,0.0*
1,1,.006,-.00525,-.0126*
20,1,.006,-.00525,-.0126,-.00945,-.01995,0.0*
1,1,.006,-.00945,-.01995*
20,1,.006,-.00945,-.01995,-.01575,-.02625,0.0*
1,1,.006,-.01575,-.02625*
20,1,.006,-.01575,-.02625,-.0231,-.03045,0.0*
1,1,.006,-.0231,-.03045*
20,1,.006,-.0231,-.03045,-.0315,-.0315,0.0*
1,1,.006,-.0315,-.0315*
1,1,.006,.00526,-.0315*
20,1,.006,.00526,-.0315,.03151,.0315,0.0*
1,1,.006,.03151,.0315*
20,1,.006,.03151,.0315,.05776,-.0315,0.0*
1,1,.006,.05776,-.0315*
1,1,.006,.04831,-.00945*
20,1,.006,.04831,-.00945,.01471,-.00945,0.0*
1,1,.006,.01471,-.00945*
%
%ADD31MACRO31*%
%AMMACRO10*
1,1,.006,.008,0.0*
20,1,.006,.008,0.0,.004,.006928,0.0*
1,1,.006,.004,.006928*
20,1,.006,.004,.006928,-.004,.006928,0.0*
1,1,.006,-.004,.006928*
20,1,.006,-.004,.006928,-.008,0.0,0.0*
1,1,.006,-.008,0.0*
20,1,.006,-.008,0.0,-.004,-.006928,0.0*
1,1,.006,-.004,-.006928*
20,1,.006,-.004,-.006928,.004,-.006928,0.0*
1,1,.006,.004,-.006928*
20,1,.006,.004,-.006928,.008,0.0,0.0*
1,1,.006,.008,0.0*
1,1,.006,-.00293,-.0024*
20,1,.006,-.00293,-.0024,-.00213,-.00333,0.0*
1,1,.006,-.00213,-.00333*
20,1,.006,-.00213,-.00333,-.00107,-.00387,0.0*
1,1,.006,-.00107,-.00387*
20,1,.006,-.00107,-.00387,.00013,-.004,0.0*
1,1,.006,.00013,-.004*
20,1,.006,.00013,-.004,.0012,-.00387,0.0*
1,1,.006,.0012,-.00387*
20,1,.006,.0012,-.00387,.00227,-.0032,0.0*
1,1,.006,.00227,-.0032*
20,1,.006,.00227,-.0032,.00293,-.0024,0.0*
1,1,.006,.00293,-.0024*
20,1,.006,.00293,-.0024,.00307,-.0016,0.0*
1,1,.006,.00307,-.0016*
20,1,.006,.00307,-.0016,.0028,-.00067,0.0*
1,1,.006,.0028,-.00067*
20,1,.006,.0028,-.00067,.00187,0.0,0.0*
1,1,.006,.00187,0.0*
20,1,.006,.00187,0.0,.00093,.00027,0.0*
1,1,.006,.00093,.00027*
20,1,.006,.00093,.00027,-.00027,.00027,0.0*
1,1,.006,-.00027,.00027*
1,1,.006,.00093,.00027*
20,1,.006,.00093,.00027,.00173,.00067,0.0*
1,1,.006,.00173,.00067*
20,1,.006,.00173,.00067,.0024,.00133,0.0*
1,1,.006,.0024,.00133*
20,1,.006,.0024,.00133,.00267,.00213,0.0*
1,1,.006,.00267,.00213*
20,1,.006,.00267,.00213,.0024,.00293,0.0*
1,1,.006,.0024,.00293*
20,1,.006,.0024,.00293,.00173,.0036,0.0*
1,1,.006,.00173,.0036*
20,1,.006,.00173,.0036,.00053,.004,0.0*
1,1,.006,.00053,.004*
20,1,.006,.00053,.004,-.00067,.00387,0.0*
1,1,.006,-.00067,.00387*
20,1,.006,-.00067,.00387,-.00187,.00333,0.0*
1,1,.006,-.00187,.00333*
%
%ADD10MACRO10*%
%AMMACRO29*
1,1,.006,-.0045,.0135*
20,1,.006,-.0045,.0135,.0045,.0135,0.0*
1,1,.006,.0045,.0135*
20,1,.006,.0045,.0135,.006844,.013295,0.0*
1,1,.006,.006844,.013295*
20,1,.006,.006844,.013295,.009117,.012686,0.0*
1,1,.006,.009117,.012686*
20,1,.006,.009117,.012686,.01125,.011691,0.0*
1,1,.006,.01125,.011691*
20,1,.006,.01125,.011691,.013178,.010342,0.0*
1,1,.006,.013178,.010342*
20,1,.006,.013178,.010342,.014842,.008678,0.0*
1,1,.006,.014842,.008678*
20,1,.006,.014842,.008678,.016191,.00675,0.0*
1,1,.006,.016191,.00675*
20,1,.006,.016191,.00675,.017186,.004617,0.0*
1,1,.006,.017186,.004617*
20,1,.006,.017186,.004617,.017795,.002344,0.0*
1,1,.006,.017795,.002344*
20,1,.006,.017795,.002344,.018,0.0,0.0*
1,1,.006,.018,0.0*
20,1,.006,.018,0.0,.017795,-.002344,0.0*
1,1,.006,.017795,-.002344*
20,1,.006,.017795,-.002344,.017186,-.004617,0.0*
1,1,.006,.017186,-.004617*
20,1,.006,.017186,-.004617,.016191,-.00675,0.0*
1,1,.006,.016191,-.00675*
20,1,.006,.016191,-.00675,.014842,-.008678,0.0*
1,1,.006,.014842,-.008678*
20,1,.006,.014842,-.008678,.013178,-.010342,0.0*
1,1,.006,.013178,-.010342*
20,1,.006,.013178,-.010342,.01125,-.011691,0.0*
1,1,.006,.01125,-.011691*
20,1,.006,.01125,-.011691,.009117,-.012686,0.0*
1,1,.006,.009117,-.012686*
20,1,.006,.009117,-.012686,.006844,-.013295,0.0*
1,1,.006,.006844,-.013295*
20,1,.006,.006844,-.013295,.0045,-.0135,0.0*
1,1,.006,.0045,-.0135*
20,1,.006,.0045,-.0135,-.0045,-.0135,0.0*
1,1,.006,-.0045,-.0135*
20,1,.006,-.0045,-.0135,-.006844,-.013295,0.0*
1,1,.006,-.006844,-.013295*
20,1,.006,-.006844,-.013295,-.009117,-.012686,0.0*
1,1,.006,-.009117,-.012686*
20,1,.006,-.009117,-.012686,-.01125,-.011691,0.0*
1,1,.006,-.01125,-.011691*
20,1,.006,-.01125,-.011691,-.013178,-.010342,0.0*
1,1,.006,-.013178,-.010342*
20,1,.006,-.013178,-.010342,-.014842,-.008678,0.0*
1,1,.006,-.014842,-.008678*
20,1,.006,-.014842,-.008678,-.016191,-.00675,0.0*
1,1,.006,-.016191,-.00675*
20,1,.006,-.016191,-.00675,-.017186,-.004617,0.0*
1,1,.006,-.017186,-.004617*
20,1,.006,-.017186,-.004617,-.017795,-.002344,0.0*
1,1,.006,-.017795,-.002344*
20,1,.006,-.017795,-.002344,-.018,0.0,0.0*
1,1,.006,-.018,0.0*
20,1,.006,-.018,0.0,-.017795,.002344,0.0*
1,1,.006,-.017795,.002344*
20,1,.006,-.017795,.002344,-.017186,.004617,0.0*
1,1,.006,-.017186,.004617*
20,1,.006,-.017186,.004617,-.016191,.00675,0.0*
1,1,.006,-.016191,.00675*
20,1,.006,-.016191,.00675,-.014842,.008678,0.0*
1,1,.006,-.014842,.008678*
20,1,.006,-.014842,.008678,-.013178,.010342,0.0*
1,1,.006,-.013178,.010342*
20,1,.006,-.013178,.010342,-.01125,.011691,0.0*
1,1,.006,-.01125,.011691*
20,1,.006,-.01125,.011691,-.009117,.012686,0.0*
1,1,.006,-.009117,.012686*
20,1,.006,-.009117,.012686,-.006844,.013295,0.0*
1,1,.006,-.006844,.013295*
20,1,.006,-.006844,.013295,-.0045,.0135,0.0*
1,1,.006,-.0045,.0135*
1,1,.006,0.0,-.00675*
20,1,.006,0.0,-.00675,.00157,-.00653,0.0*
1,1,.006,.00157,-.00653*
20,1,.006,.00157,-.00653,.00337,-.00585,0.0*
1,1,.006,.00337,-.00585*
20,1,.006,.00337,-.00585,.0045,-.00473,0.0*
1,1,.006,.0045,-.00473*
20,1,.006,.0045,-.00473,.00495,-.00315,0.0*
1,1,.006,.00495,-.00315*
20,1,.006,.00495,-.00315,.0045,-.00158,0.0*
1,1,.006,.0045,-.00158*
20,1,.006,.0045,-.00158,.00315,-.00023,0.0*
1,1,.006,.00315,-.00023*
20,1,.006,.00315,-.00023,.00112,.00045,0.0*
1,1,.006,.00112,.00045*
20,1,.006,.00112,.00045,-.00112,.00045,0.0*
1,1,.006,-.00112,.00045*
20,1,.006,-.00112,.00045,-.00248,.0009,0.0*
1,1,.006,-.00248,.0009*
20,1,.006,-.00248,.0009,-.0036,.00202,0.0*
1,1,.006,-.0036,.00202*
20,1,.006,-.0036,.00202,-.00405,.0036,0.0*
1,1,.006,-.00405,.0036*
20,1,.006,-.00405,.0036,-.00337,.00517,0.0*
1,1,.006,-.00337,.00517*
20,1,.006,-.00337,.00517,-.0018,.0063,0.0*
1,1,.006,-.0018,.0063*
20,1,.006,-.0018,.0063,0.0,.00675,0.0*
1,1,.006,0.0,.00675*
20,1,.006,0.0,.00675,.0018,.0063,0.0*
1,1,.006,.0018,.0063*
20,1,.006,.0018,.0063,.00337,.00517,0.0*
1,1,.006,.00337,.00517*
20,1,.006,.00337,.00517,.00405,.0036,0.0*
1,1,.006,.00405,.0036*
20,1,.006,.00405,.0036,.0036,.00202,0.0*
1,1,.006,.0036,.00202*
20,1,.006,.0036,.00202,.00248,.0009,0.0*
1,1,.006,.00248,.0009*
20,1,.006,.00248,.0009,.00112,.00045,0.0*
1,1,.006,.00112,.00045*
20,1,.006,.00112,.00045,-.00112,.00045,0.0*
1,1,.006,-.00112,.00045*
20,1,.006,-.00112,.00045,-.00315,-.00023,0.0*
1,1,.006,-.00315,-.00023*
20,1,.006,-.00315,-.00023,-.0045,-.00158,0.0*
1,1,.006,-.0045,-.00158*
20,1,.006,-.0045,-.00158,-.00495,-.00315,0.0*
1,1,.006,-.00495,-.00315*
20,1,.006,-.00495,-.00315,-.0045,-.00473,0.0*
1,1,.006,-.0045,-.00473*
20,1,.006,-.0045,-.00473,-.00337,-.00585,0.0*
1,1,.006,-.00337,-.00585*
20,1,.006,-.00337,-.00585,-.00157,-.00653,0.0*
1,1,.006,-.00157,-.00653*
20,1,.006,-.00157,-.00653,0.0,-.00675,0.0*
1,1,.006,0.0,-.00675*
%
%ADD29MACRO29*%
%AMMACRO17*
1,1,.006,0.0,.0175*
20,1,.006,0.0,.0175,.0175,-.0175,0.0*
1,1,.006,.0175,-.0175*
20,1,.006,.0175,-.0175,-.0175,-.0175,0.0*
1,1,.006,-.0175,-.0175*
20,1,.006,-.0175,-.0175,0.0,.0175,0.0*
1,1,.006,0.0,.0175*
1,1,.006,-.00058,-.00875*
20,1,.006,-.00058,-.00875,0.0,-.00496,0.0*
1,1,.006,0.0,-.00496*
20,1,.006,0.0,-.00496,.00088,-.00175,0.0*
1,1,.006,.00088,-.00175*
20,1,.006,.00088,-.00175,.00204,.00117,0.0*
1,1,.006,.00204,.00117*
20,1,.006,.00204,.00117,.0035,.00437,0.0*
1,1,.006,.0035,.00437*
20,1,.006,.0035,.00437,.00583,.00875,0.0*
1,1,.006,.00583,.00875*
20,1,.006,.00583,.00875,-.00583,.00875,0.0*
1,1,.006,-.00583,.00875*
%
%ADD17MACRO17*%
%AMMACRO25*
1,1,.006,0.0,.0145*
20,1,.006,0.0,.0145,-.012557,.00725,0.0*
1,1,.006,-.012557,.00725*
20,1,.006,-.012557,.00725,-.012557,-.00725,0.0*
1,1,.006,-.012557,-.00725*
20,1,.006,-.012557,-.00725,0.0,-.0145,0.0*
1,1,.006,0.0,-.0145*
20,1,.006,0.0,-.0145,.012557,-.00725,0.0*
1,1,.006,.012557,-.00725*
20,1,.006,.012557,-.00725,.012557,.00725,0.0*
1,1,.006,.012557,.00725*
20,1,.006,.012557,.00725,0.0,.0145,0.0*
1,1,.006,0.0,.0145*
1,1,.006,.0029,-.00725*
20,1,.006,.0029,-.00725,.0029,.00725,0.0*
1,1,.006,.0029,.00725*
20,1,.006,.0029,.00725,-.00604,-.00314,0.0*
1,1,.006,-.00604,-.00314*
20,1,.006,-.00604,-.00314,.00604,-.00314,0.0*
1,1,.006,.00604,-.00314*
%
%ADD25MACRO25*%
%AMMACRO33*
1,1,.006,-.01425,.00475*
20,1,.006,-.01425,.00475,-.014034,.007224,0.0*
1,1,.006,-.014034,.007224*
20,1,.006,-.014034,.007224,-.013391,.009624,0.0*
1,1,.006,-.013391,.009624*
20,1,.006,-.013391,.009624,-.012341,.011875,0.0*
1,1,.006,-.012341,.011875*
20,1,.006,-.012341,.011875,-.010916,.01391,0.0*
1,1,.006,-.010916,.01391*
20,1,.006,-.010916,.01391,-.00916,.015666,0.0*
1,1,.006,-.00916,.015666*
20,1,.006,-.00916,.015666,-.007125,.017091,0.0*
1,1,.006,-.007125,.017091*
20,1,.006,-.007125,.017091,-.004874,.018141,0.0*
1,1,.006,-.004874,.018141*
20,1,.006,-.004874,.018141,-.002474,.018784,0.0*
1,1,.006,-.002474,.018784*
20,1,.006,-.002474,.018784,0.0,.019,0.0*
1,1,.006,0.0,.019*
20,1,.006,0.0,.019,.002474,.018784,0.0*
1,1,.006,.002474,.018784*
20,1,.006,.002474,.018784,.004874,.018141,0.0*
1,1,.006,.004874,.018141*
20,1,.006,.004874,.018141,.007125,.017091,0.0*
1,1,.006,.007125,.017091*
20,1,.006,.007125,.017091,.00916,.015666,0.0*
1,1,.006,.00916,.015666*
20,1,.006,.00916,.015666,.010916,.01391,0.0*
1,1,.006,.010916,.01391*
20,1,.006,.010916,.01391,.012341,.011875,0.0*
1,1,.006,.012341,.011875*
20,1,.006,.012341,.011875,.013391,.009624,0.0*
1,1,.006,.013391,.009624*
20,1,.006,.013391,.009624,.014034,.007224,0.0*
1,1,.006,.014034,.007224*
20,1,.006,.014034,.007224,.01425,.00475,0.0*
1,1,.006,.01425,.00475*
20,1,.006,.01425,.00475,.01425,-.00475,0.0*
1,1,.006,.01425,-.00475*
20,1,.006,.01425,-.00475,.014034,-.007224,0.0*
1,1,.006,.014034,-.007224*
20,1,.006,.014034,-.007224,.013391,-.009624,0.0*
1,1,.006,.013391,-.009624*
20,1,.006,.013391,-.009624,.012341,-.011875,0.0*
1,1,.006,.012341,-.011875*
20,1,.006,.012341,-.011875,.010916,-.01391,0.0*
1,1,.006,.010916,-.01391*
20,1,.006,.010916,-.01391,.00916,-.015666,0.0*
1,1,.006,.00916,-.015666*
20,1,.006,.00916,-.015666,.007125,-.017091,0.0*
1,1,.006,.007125,-.017091*
20,1,.006,.007125,-.017091,.004874,-.018141,0.0*
1,1,.006,.004874,-.018141*
20,1,.006,.004874,-.018141,.002474,-.018784,0.0*
1,1,.006,.002474,-.018784*
20,1,.006,.002474,-.018784,0.0,-.019,0.0*
1,1,.006,0.0,-.019*
20,1,.006,0.0,-.019,-.002474,-.018784,0.0*
1,1,.006,-.002474,-.018784*
20,1,.006,-.002474,-.018784,-.004874,-.018141,0.0*
1,1,.006,-.004874,-.018141*
20,1,.006,-.004874,-.018141,-.007125,-.017091,0.0*
1,1,.006,-.007125,-.017091*
20,1,.006,-.007125,-.017091,-.00916,-.015666,0.0*
1,1,.006,-.00916,-.015666*
20,1,.006,-.00916,-.015666,-.010916,-.01391,0.0*
1,1,.006,-.010916,-.01391*
20,1,.006,-.010916,-.01391,-.012341,-.011875,0.0*
1,1,.006,-.012341,-.011875*
20,1,.006,-.012341,-.011875,-.013391,-.009624,0.0*
1,1,.006,-.013391,-.009624*
20,1,.006,-.013391,-.009624,-.014034,-.007224,0.0*
1,1,.006,-.014034,-.007224*
20,1,.006,-.014034,-.007224,-.01425,-.00475,0.0*
1,1,.006,-.01425,-.00475*
20,1,.006,-.01425,-.00475,-.01425,.00475,0.0*
1,1,.006,-.01425,.00475*
1,1,.006,-.00403,-.00546*
20,1,.006,-.00403,-.00546,-.00237,-.00665,0.0*
1,1,.006,-.00237,-.00665*
20,1,.006,-.00237,-.00665,-.00047,-.00712,0.0*
1,1,.006,-.00047,-.00712*
20,1,.006,-.00047,-.00712,.00143,-.00665,0.0*
1,1,.006,.00143,-.00665*
20,1,.006,.00143,-.00665,.00309,-.00522,0.0*
1,1,.006,.00309,-.00522*
20,1,.006,.00309,-.00522,.00428,-.00308,0.0*
1,1,.006,.00428,-.00308*
20,1,.006,.00428,-.00308,.00476,-.00095,0.0*
1,1,.006,.00476,-.00095*
20,1,.006,.00476,-.00095,.00476,.00167,0.0*
1,1,.006,.00476,.00167*
20,1,.006,.00476,.00167,.00428,.0038,0.0*
1,1,.006,.00428,.0038*
20,1,.006,.00428,.0038,.00309,.0057,0.0*
1,1,.006,.00309,.0057*
20,1,.006,.00309,.0057,.00167,.00666,0.0*
1,1,.006,.00167,.00666*
20,1,.006,.00167,.00666,0.0,.00713,0.0*
1,1,.006,0.0,.00713*
20,1,.006,0.0,.00713,-.0019,.00666,0.0*
1,1,.006,-.0019,.00666*
20,1,.006,-.0019,.00666,-.00332,.0057,0.0*
1,1,.006,-.00332,.0057*
20,1,.006,-.00332,.0057,-.00427,.00428,0.0*
1,1,.006,-.00427,.00428*
20,1,.006,-.00427,.00428,-.00475,.00238,0.0*
1,1,.006,-.00475,.00238*
20,1,.006,-.00475,.00238,-.00427,.00072,0.0*
1,1,.006,-.00427,.00072*
20,1,.006,-.00427,.00072,-.00308,-.00095,0.0*
1,1,.006,-.00308,-.00095*
20,1,.006,-.00308,-.00095,-.00166,-.0019,0.0*
1,1,.006,-.00166,-.0019*
20,1,.006,-.00166,-.0019,0.0,-.00213,0.0*
1,1,.006,0.0,-.00213*
20,1,.006,0.0,-.00213,.0019,-.00166,0.0*
1,1,.006,.0019,-.00166*
20,1,.006,.0019,-.00166,.00333,-.00047,0.0*
1,1,.006,.00333,-.00047*
20,1,.006,.00333,-.00047,.00476,.00167,0.0*
1,1,.006,.00476,.00167*
%
%ADD33MACRO33*%
%ADD39C,.02*%
%ADD40C,.006*%
G75*
%LPD*%
G75*
G54D10*
X8590Y318590D03*
X4500Y329297D03*
Y349297D03*
Y369297D03*
Y389297D03*
Y409297D03*
Y429297D03*
Y449297D03*
Y469297D03*
Y489297D03*
Y509297D03*
Y529297D03*
Y549297D03*
Y569297D03*
Y589297D03*
Y609297D03*
Y629297D03*
Y649297D03*
Y669297D03*
Y689297D03*
Y709297D03*
Y729297D03*
Y749297D03*
Y769297D03*
Y789297D03*
Y809297D03*
Y829297D03*
Y849297D03*
Y869297D03*
Y889297D03*
Y909297D03*
Y929297D03*
Y949297D03*
Y969297D03*
X20000Y380000D03*
Y440000D03*
Y460000D03*
Y480000D03*
Y500000D03*
X25000Y980000D03*
X45000D03*
X55000Y975000D03*
X65000Y980000D03*
X75000Y975000D03*
X95000D03*
X121000Y545500D03*
X146364Y296000D03*
X140000Y720000D03*
Y740000D03*
X156500Y939500D03*
X162000D03*
X168000Y575000D03*
Y580000D03*
X178000Y590000D03*
X180000Y760000D03*
X167500Y939500D03*
X172500D03*
X177500D03*
X182000D03*
X188000D03*
X193500D03*
X199500D03*
X207100Y703600D03*
X206000Y982000D03*
X222000Y703500D03*
X220000Y760000D03*
X224000Y875000D03*
X225500Y879500D03*
X225000Y920500D03*
X232000Y921000D03*
X227500Y957500D03*
Y963500D03*
X226000Y982000D03*
X247500Y883000D03*
X243000D03*
X246968Y957784D03*
X233468Y957284D03*
X239968Y957784D03*
X246968Y963784D03*
X239968D03*
X233468D03*
X246000Y982000D03*
X261500Y188900D03*
X256300Y188800D03*
X258800Y184200D03*
X261400Y179800D03*
X255800Y179600D03*
X259000Y211000D03*
Y206000D03*
X262500Y208500D03*
X260000Y260000D03*
Y760000D03*
X252000Y883000D03*
X256500D03*
X261000D03*
X265500D03*
X252000Y957500D03*
X252500Y963500D03*
X262178Y976000D03*
X261178Y981040D03*
X281800Y183700D03*
Y188500D03*
X281900Y178500D03*
X278500Y965000D03*
X277500Y969500D03*
X272500D03*
X268000D03*
X296000Y105000D03*
X285800Y180800D03*
X285600Y186100D03*
X285500Y330000D03*
X286000Y336000D03*
X285678Y995500D03*
X293178D03*
X299500Y5500D03*
X306000Y105000D03*
X301000D03*
X310929Y257500D03*
X311500Y272000D03*
X311429Y334500D03*
X307429Y336000D03*
Y331500D03*
X301178Y995500D03*
X309678D03*
X320500Y11000D03*
X316000D03*
X324000Y24000D03*
Y19500D03*
Y15000D03*
X321000Y29000D03*
Y33500D03*
Y38000D03*
X330500Y38500D03*
Y33500D03*
X321000Y57000D03*
Y52500D03*
Y48000D03*
Y42500D03*
Y61500D03*
X315929Y253000D03*
X316000Y271500D03*
X315929Y257500D03*
X322429Y349300D03*
X324678Y995500D03*
X317178D03*
X344000Y27000D03*
X336000D03*
X337500Y102000D03*
X335645Y445630D03*
X341178Y996000D03*
X332678Y995500D03*
X349000Y38500D03*
Y33500D03*
X362500Y64000D03*
X351929Y266000D03*
X352429Y279000D03*
X357929Y277000D03*
X357661Y434216D03*
X364055Y428500D03*
X361055Y431500D03*
X362500Y608500D03*
X355500D03*
Y614000D03*
X362500D03*
X358268Y995500D03*
X348678Y996000D03*
X370000Y51000D03*
Y55500D03*
Y60000D03*
X370500Y72100D03*
X366000Y277500D03*
X376500Y608500D03*
X369500D03*
Y614000D03*
X376500D03*
X378500Y812000D03*
Y824500D03*
X377953Y995725D03*
X393800Y25100D03*
X389300Y20100D03*
X393800D03*
X384800Y25100D03*
X389300D03*
X384800Y20100D03*
X391000Y35500D03*
X395500D03*
X393900Y30400D03*
X389400D03*
X384900D03*
X386000Y53000D03*
X381500D03*
Y58000D03*
X389763Y996085D03*
X398300Y20100D03*
Y25100D03*
X400000Y35500D03*
X398400Y30400D03*
X398000Y39500D03*
X403155Y437600D03*
X406500Y713500D03*
X412000Y724000D03*
X409500Y775500D03*
X422500Y764500D03*
X445395Y317610D03*
X431000Y713500D03*
Y724000D03*
X432678Y827300D03*
X430778Y864000D03*
X435678Y996000D03*
X443178D03*
X453878Y824900D03*
X456278Y866500D03*
X458678Y996000D03*
X450178D03*
X467000Y118500D03*
X477500Y715000D03*
X474178Y995500D03*
X466178Y996000D03*
X482429Y139000D03*
X491500Y715000D03*
X490500Y800000D03*
X482778Y832000D03*
X482278Y867500D03*
X495000Y883000D03*
X489678Y995500D03*
X482178D03*
X504500Y715000D03*
X502500Y800000D03*
X501000Y876000D03*
X499000Y883000D03*
X505678Y995500D03*
X498178D03*
X516000Y134000D03*
X519929Y135500D03*
X521055Y528500D03*
Y533500D03*
X516555Y528500D03*
Y533500D03*
X526055D03*
X526000Y524500D03*
Y529000D03*
X521000Y524000D03*
X521055Y544000D03*
Y548900D03*
X516555Y543500D03*
X516655Y548900D03*
X521055Y538500D03*
X516555Y539000D03*
X526055Y538500D03*
Y544000D03*
Y548900D03*
X516500Y556000D03*
X521178Y995500D03*
X513678D03*
X536678Y996000D03*
X530083Y995500D03*
X560000Y20000D03*
X560678Y996000D03*
X567500Y457500D03*
X563000Y453000D03*
X567500D03*
Y462000D03*
Y466500D03*
X563000Y457500D03*
Y462000D03*
Y466500D03*
X569178Y996000D03*
X576678D03*
X591000Y253500D03*
Y262500D03*
X586000Y267000D03*
Y262500D03*
X591000Y258000D03*
X586150Y383000D03*
X586200Y378500D03*
X581950Y383000D03*
X582000Y378500D03*
X590500Y383000D03*
X586150Y396000D03*
X590500D03*
X581950D03*
X586150Y409500D03*
X581950D03*
X590500D03*
X582700Y431500D03*
X590500Y423500D03*
X586150D03*
X587000Y431500D03*
X578500D03*
X581950Y423500D03*
X582200Y439500D03*
X578000D03*
X586500D03*
X593500Y648500D03*
Y659500D03*
Y654000D03*
X584678Y994500D03*
X595500Y253500D03*
Y258000D03*
X610500Y333000D03*
X606000Y341500D03*
X609000Y345500D03*
X610000Y415500D03*
Y434000D03*
Y428500D03*
Y422000D03*
X610100Y439500D03*
X602500Y465900D03*
X608000Y465800D03*
X602500Y470100D03*
X608000Y470300D03*
X601000Y543000D03*
X599500Y648500D03*
Y654000D03*
Y659500D03*
X604500Y714500D03*
X609500Y778500D03*
X603000D03*
Y785000D03*
X609000Y870000D03*
X604000Y877500D03*
X609211Y877611D03*
X606000Y918500D03*
X598178Y983500D03*
X615000Y333000D03*
X620500D03*
X611500Y341500D03*
X613500Y345500D03*
X616500Y341500D03*
X621500D03*
X614200Y415500D03*
X614500Y434000D03*
X614200Y422000D03*
Y428500D03*
X614300Y439500D03*
X620000Y465800D03*
X613500D03*
X626500D03*
X613500Y470000D03*
X620000D03*
X626500D03*
Y557350D03*
X616500Y714500D03*
X613500Y744500D03*
Y759000D03*
X620500Y848500D03*
X642000Y335000D03*
X639000Y332000D03*
X637500Y367900D03*
X630500Y368500D03*
X642000D03*
X638500Y409000D03*
X634500Y427000D03*
X637000Y431500D03*
X632500D03*
X637000Y436500D03*
X632500D03*
X634000Y734500D03*
X633500Y749500D03*
X630500Y912000D03*
X650000Y110000D03*
X647500Y368500D03*
X653500D03*
X659500D03*
X651500Y408500D03*
X646500D03*
X645500Y481000D03*
X657500Y827000D03*
X656500Y906000D03*
X674666Y82002D03*
X670454Y94544D03*
X670998Y116010D03*
X660000Y120000D03*
X670522Y130200D03*
X673500Y334000D03*
X668000D03*
X662000D03*
X665000Y368500D03*
X670000Y395000D03*
X670500Y414000D03*
X685898Y133380D03*
X682418Y129980D03*
X690966Y142028D03*
X685000Y150500D03*
X690500Y468000D03*
X682500Y917500D03*
X701949Y118331D03*
X701828Y129550D03*
X698500Y132500D03*
X697248Y128000D03*
X703053Y133568D03*
X704716Y156520D03*
X700216Y156368D03*
X705500Y352500D03*
X707000Y340500D03*
X708500Y365000D03*
X707000Y385000D03*
Y378000D03*
X708500Y371000D03*
X694000Y483500D03*
X693500Y472000D03*
X694000Y492000D03*
Y500500D03*
Y507500D03*
Y514000D03*
X722716Y156520D03*
X718216D03*
X713716D03*
X709216D03*
X719500Y185600D03*
X725000Y189000D03*
X711500Y385000D03*
Y378000D03*
X720000Y849000D03*
X721900Y852750D03*
X720000Y905000D03*
X730748Y99500D03*
X740000Y109534D03*
X732248Y140000D03*
X731716Y156500D03*
X736000Y142000D03*
X727248Y141500D03*
X727216Y156520D03*
X740000Y681000D03*
X740500Y755000D03*
X739900Y760000D03*
X746716Y130238D03*
X750916Y130272D03*
X757000Y435500D03*
X752100Y435600D03*
X751500Y431000D03*
X756500D03*
X757802Y474000D03*
X760522Y116784D03*
X770000Y123500D03*
X773000Y339500D03*
X761600Y435600D03*
X761500Y431000D03*
X766000D03*
X770000Y677000D03*
Y681500D03*
X767000Y845000D03*
X773000Y917000D03*
Y921500D03*
Y927000D03*
X767500D03*
X771000Y958500D03*
X766600D03*
X762100Y958600D03*
X771500Y963500D03*
X767100D03*
X762600Y963600D03*
X771400Y968900D03*
X767000D03*
X762500Y969000D03*
X777500Y351000D03*
X782500D03*
X777500Y339500D03*
X782400Y339400D03*
X782600Y411000D03*
X776468Y447600D03*
X800000Y100000D03*
X792000Y356500D03*
X801500Y573000D03*
X800500Y977500D03*
X794500D03*
X800500Y982000D03*
X794500D03*
X810000Y120000D03*
X818500Y361600D03*
X813500Y367000D03*
X819000Y473000D03*
X820500Y754000D03*
Y765500D03*
X828500Y361500D03*
X837000D03*
X829500Y373500D03*
Y380000D03*
Y385500D03*
X846500Y362000D03*
X842000Y367000D03*
Y372000D03*
Y377500D03*
X848600Y517100D03*
X843100Y517000D03*
X843200Y512800D03*
X843300Y507900D03*
X848800Y508000D03*
X848700Y512900D03*
X854500Y778000D03*
X850000D03*
X854500Y783000D03*
X850000D03*
X870000Y160000D03*
X858500Y656500D03*
X879736Y290000D03*
X875500Y290500D03*
X878500Y294178D03*
X884000Y396500D03*
X879500D03*
X889000Y617000D03*
X895000Y96000D03*
X899500Y92500D03*
X890000Y140000D03*
X899000Y405500D03*
X894000D03*
X899000Y410500D03*
X894000D03*
X895000Y617500D03*
X910000Y160000D03*
X915000Y805000D03*
Y825000D03*
Y845000D03*
Y865000D03*
Y885000D03*
Y905000D03*
Y925000D03*
Y945000D03*
Y965000D03*
X930500Y219000D03*
X936500D03*
X930500Y232000D03*
X936500D03*
Y225500D03*
X930500D03*
Y536500D03*
X943500Y488000D03*
X966000Y209500D03*
X961000Y212500D03*
X963500Y488000D03*
Y536500D03*
Y654500D03*
X958000D03*
Y659500D03*
X963500D03*
X969000Y655100D03*
Y659500D03*
X965000Y725500D03*
X981000Y386500D03*
X985000Y388000D03*
X980500Y391000D03*
X984500Y392500D03*
X974500Y655100D03*
Y659500D03*
X980000Y725500D03*
X1004500Y84000D03*
X1000500Y667500D03*
X990000D03*
X1007000Y12000D03*
X1013500Y84000D03*
X1009000D03*
X1016500Y75500D03*
X1013000Y282500D03*
X1012900Y275300D03*
X1011500Y642000D03*
Y648000D03*
X1020500Y882500D03*
Y887000D03*
X1022500Y51500D03*
X1034500D03*
X1028000D03*
X1021000Y75500D03*
X1032000Y82500D03*
Y90000D03*
Y97000D03*
Y103500D03*
Y110000D03*
X1031800Y248800D03*
X1027500Y248500D03*
X1036300Y248800D03*
X1033000Y290000D03*
X1027500D03*
X1027700Y294200D03*
X1033200D03*
X1035500Y825500D03*
Y830000D03*
X1035000Y970000D03*
X1053000Y228000D03*
X1046000Y290000D03*
X1039500D03*
X1039700Y294200D03*
X1046200D03*
X1040000Y825500D03*
X1044500D03*
X1049000D03*
X1053400D03*
X1040000Y830000D03*
X1051000Y883600D03*
Y888500D03*
X1065000Y154000D03*
X1057000Y229500D03*
X1056716Y224500D03*
X1060500Y282500D03*
X1060600Y303150D03*
X1056100Y303200D03*
X1059900Y295200D03*
X1059800Y290600D03*
X1058000Y889500D03*
Y902500D03*
Y896000D03*
X1060000Y929500D03*
X1055000Y970000D03*
X1084988Y154203D03*
X1080500Y153500D03*
X1077500Y150000D03*
X1085150Y158400D03*
X1086000Y187500D03*
Y192500D03*
X1079000Y434000D03*
X1085000D03*
X1079100Y429000D03*
X1075000Y970000D03*
X1100000Y180000D03*
X1101500Y461500D03*
X1102500Y762500D03*
X1097500D03*
X1102500Y767400D03*
X1097500D03*
X1093000Y766500D03*
X1097500Y797500D03*
X1091500Y846500D03*
X1105000Y400500D03*
X1106600Y753000D03*
X1114500Y855500D03*
X1119000D03*
X1105000Y970000D03*
X1134000Y229000D03*
X1128500D03*
X1129000Y502500D03*
X1123500D03*
Y507500D03*
X1129000D03*
X1135500D03*
Y502500D03*
X1125000Y970000D03*
X1141000Y507500D03*
Y502500D03*
X1137000Y890000D03*
X1144500D03*
X1152000D03*
X1145000Y970000D03*
X1161500Y222000D03*
X1166500D03*
X1160500Y242000D03*
Y246500D03*
X1165000Y242000D03*
Y246500D03*
X1158000Y890000D03*
X1164500D03*
X1171000Y222000D03*
X1176000D03*
X1169000Y398000D03*
X1171000Y394000D03*
X1170500Y461000D03*
X1173100Y499200D03*
X1182000Y816000D03*
X1181500Y820500D03*
X1177000D03*
X1175000Y970000D03*
X1199100Y226600D03*
X1194900D03*
X1195000Y422500D03*
X1194000Y484000D03*
X1189500D03*
X1194000Y488500D03*
X1189500D03*
Y492900D03*
X1194000Y493000D03*
X1188500Y500000D03*
X1195920Y753700D03*
X1195000Y970000D03*
X1203500Y193800D03*
Y198000D03*
X1208000D03*
Y193800D03*
X1204000Y206000D03*
X1208500Y207000D03*
X1204000Y210500D03*
Y215000D03*
X1207500Y225000D03*
X1203300Y226600D03*
X1217000Y537000D03*
X1216500Y710125D03*
X1215000Y970000D03*
X1249300Y166000D03*
X1240600Y167000D03*
X1240700Y171200D03*
X1240800Y179800D03*
X1240700Y175500D03*
Y184000D03*
X1241000Y219000D03*
X1239500Y227500D03*
X1242000Y223500D03*
X1244000Y227500D03*
X1246000Y263500D03*
X1263000Y717000D03*
X1281000Y475000D03*
X1276500D03*
X1277500Y757500D03*
Y778500D03*
X1287500Y428000D03*
X1288000Y442000D03*
X1292500Y441000D03*
X1285500Y475000D03*
X1293500D03*
X1308500Y771500D03*
X1303000D03*
X1314000D03*
X1324500Y345400D03*
Y341000D03*
X1329000Y341100D03*
Y345500D03*
X1323000Y368000D03*
X1327500D03*
X1332000D03*
X1318000Y369500D03*
X1332000Y372400D03*
X1327500D03*
X1323000D03*
X1318000Y375500D03*
Y381500D03*
X1330000Y428000D03*
X1331500Y432500D03*
X1338000Y341100D03*
X1333500D03*
Y345500D03*
X1338000D03*
X1358500Y346500D03*
Y351000D03*
X1354000D03*
Y346500D03*
X1354500Y480500D03*
Y475000D03*
X1360500D03*
Y480500D03*
X1354500Y486500D03*
X1360500D03*
X1360000Y631500D03*
X1355500Y631000D03*
X1358000Y626000D03*
X1357500Y635500D03*
X1351000Y677000D03*
Y672000D03*
X1355000Y674500D03*
X1354500Y669000D03*
Y703500D03*
X1371500Y254000D03*
X1366000D03*
X1371500Y264000D03*
X1366000D03*
X1371500Y259500D03*
X1366000D03*
X1378500Y370000D03*
Y365000D03*
Y360000D03*
X1377000Y384000D03*
Y379000D03*
X1378500Y374500D03*
X1377000Y390000D03*
X1374500Y395000D03*
Y402000D03*
X1372500Y415000D03*
X1784450Y806050D03*
G54D20*
X200000Y391500D03*
Y401500D03*
Y411500D03*
Y421500D03*
X216500Y391500D03*
Y401500D03*
Y411500D03*
Y421500D03*
X1296000Y319500D03*
Y329500D03*
X1367067Y42323D03*
Y60039D03*
Y78544D03*
Y96260D03*
X1392657Y42323D03*
Y60039D03*
Y78544D03*
Y96260D03*
X1784450Y609350D03*
G54D11*
X19272Y337795D03*
Y396850D03*
X98838Y337795D03*
Y396850D03*
X1784450Y440750D03*
G54D12*
X21220Y373228D03*
X96890D03*
X157480Y283071D03*
X220472D03*
X1784450Y244050D03*
G54D21*
X270078Y92125D03*
Y155117D03*
X490944Y79921D03*
Y255118D03*
X743897Y353543D03*
Y410629D03*
X1305117Y87548D03*
Y262745D03*
X1376968Y147243D03*
Y216535D03*
X1784450Y159750D03*
G54D30*
X945197Y380000D03*
X968819D03*
X1784450Y328350D03*
G54D40*
G01X-185516Y-508119D02*
Y-490619D01*
G01X-176346D02*
Y-508119D01*
G01Y-499369D02*
X-185516D01*
G01X-163431Y-508119D02*
X-165178Y-507827D01*
X-166706Y-506661D01*
X-168016Y-504911D01*
X-168890Y-502869D01*
X-169326Y-500536D01*
Y-498202D01*
X-168890Y-495869D01*
X-168016Y-493827D01*
X-166706Y-492078D01*
X-165178Y-490911D01*
X-163431Y-490619D01*
X-161685Y-490911D01*
X-160156Y-492078D01*
X-158846Y-493827D01*
X-157972Y-495869D01*
X-157536Y-498202D01*
Y-500536D01*
X-157972Y-502869D01*
X-158846Y-504911D01*
X-160156Y-506661D01*
X-161685Y-507827D01*
X-163431Y-508119D01*
G01X-150953D02*
Y-490619D01*
X-140909Y-508119D01*
Y-490619D01*
G01X-124064Y-508119D02*
X-132798D01*
Y-490619D01*
X-124064D01*
G01X-127558Y-499077D02*
X-132798D01*
G01X-110931Y-508119D02*
Y-500244D01*
X-115298Y-490619D01*
G01X-106564D02*
X-110931Y-500244D01*
G01X-74185Y-498786D02*
X-73311Y-497911D01*
X-72656Y-496453D01*
X-72219Y-494410D01*
X-72656Y-492661D01*
X-73529Y-491494D01*
X-75058Y-490619D01*
X-80953D01*
Y-508119D01*
X-73748D01*
X-72219Y-506953D01*
X-71346Y-505202D01*
X-70909Y-503161D01*
X-71346Y-501119D01*
X-72656Y-499369D01*
X-74185Y-498786D01*
X-80953D01*
G01X-63890Y-508119D02*
X-58431Y-490619D01*
X-52972Y-508119D01*
G01X-54938Y-501994D02*
X-61925D01*
G01X-45734Y-508119D02*
Y-490619D01*
X-41368D01*
X-39621Y-491494D01*
X-38311Y-492661D01*
X-37219Y-494410D01*
X-36346Y-496453D01*
X-36128Y-499369D01*
X-36346Y-502286D01*
X-37219Y-504328D01*
X-38311Y-506078D01*
X-39621Y-507244D01*
X-41368Y-508119D01*
X-45734D01*
G01X-22121Y-499369D02*
X-17754D01*
Y-504619D01*
X-19064Y-506369D01*
X-20593Y-507536D01*
X-22776Y-508119D01*
X-24959Y-507536D01*
X-26488Y-506369D01*
X-27798Y-504619D01*
X-28671Y-502577D01*
X-29108Y-500244D01*
Y-498202D01*
X-28671Y-496453D01*
X-27798Y-494410D01*
X-26488Y-492661D01*
X-25178Y-491494D01*
X-23431Y-490619D01*
X-21903D01*
X-20156Y-491202D01*
X-18846Y-492369D01*
G01X-1564Y-508119D02*
X-10298D01*
Y-490619D01*
X-1564D01*
G01X-5058Y-499077D02*
X-10298D01*
G01X7202Y-508119D02*
Y-490619D01*
X12661D01*
X14407Y-491494D01*
X15499Y-492661D01*
X15936Y-494994D01*
X15499Y-497328D01*
X14189Y-498786D01*
X12661Y-499661D01*
X7202D01*
G01X12661D02*
X15936Y-508119D01*
G01X48315Y-498786D02*
X49189Y-497911D01*
X49844Y-496453D01*
X50281Y-494410D01*
X49844Y-492661D01*
X48971Y-491494D01*
X47442Y-490619D01*
X41547D01*
Y-508119D01*
X48752D01*
X50281Y-506953D01*
X51154Y-505202D01*
X51591Y-503161D01*
X51154Y-501119D01*
X49844Y-499369D01*
X48315Y-498786D01*
X41547D01*
G01X58610Y-508119D02*
X64069Y-490619D01*
X69528Y-508119D01*
G01X67562Y-501994D02*
X60575D01*
G01X76984Y-505786D02*
X78731Y-507244D01*
X80696Y-508119D01*
X82442D01*
X84189Y-507244D01*
X85499Y-505786D01*
X86154Y-503744D01*
X85717Y-501703D01*
X84626Y-499952D01*
X82661Y-498786D01*
X80041Y-498202D01*
X78512Y-497036D01*
X77857Y-494994D01*
X78294Y-492952D01*
X79386Y-491494D01*
X80914Y-490619D01*
X82442D01*
X83971Y-491202D01*
X85281Y-492661D01*
G01X103436Y-508119D02*
X94702D01*
Y-490619D01*
X103436D01*
G01X99942Y-499077D02*
X94702D01*
G01X118315Y-498786D02*
X119189Y-497911D01*
X119844Y-496453D01*
X120281Y-494410D01*
X119844Y-492661D01*
X118971Y-491494D01*
X117442Y-490619D01*
X111547D01*
Y-508119D01*
X118752D01*
X120281Y-506953D01*
X121154Y-505202D01*
X121591Y-503161D01*
X121154Y-501119D01*
X119844Y-499369D01*
X118315Y-498786D01*
X111547D01*
G01X134069Y-508119D02*
X132322Y-507827D01*
X130794Y-506661D01*
X129484Y-504911D01*
X128610Y-502869D01*
X128174Y-500536D01*
Y-498202D01*
X128610Y-495869D01*
X129484Y-493827D01*
X130794Y-492078D01*
X132322Y-490911D01*
X134069Y-490619D01*
X135815Y-490911D01*
X137344Y-492078D01*
X138654Y-493827D01*
X139528Y-495869D01*
X139964Y-498202D01*
Y-500536D01*
X139528Y-502869D01*
X138654Y-504911D01*
X137344Y-506661D01*
X135815Y-507827D01*
X134069Y-508119D01*
G01X146110D02*
X151569Y-490619D01*
X157028Y-508119D01*
G01X155062Y-501994D02*
X148075D01*
G01X164702Y-508119D02*
Y-490619D01*
X170161D01*
X171907Y-491494D01*
X172999Y-492661D01*
X173436Y-494994D01*
X172999Y-497328D01*
X171689Y-498786D01*
X170161Y-499661D01*
X164702D01*
G01X170161D02*
X173436Y-508119D01*
G01X181766D02*
Y-490619D01*
X186132D01*
X187879Y-491494D01*
X189189Y-492661D01*
X190281Y-494410D01*
X191154Y-496453D01*
X191372Y-499369D01*
X191154Y-502286D01*
X190281Y-504328D01*
X189189Y-506078D01*
X187879Y-507244D01*
X186132Y-508119D01*
X181766D01*
G01X-37858Y-463119D02*
Y-445619D01*
X-32181Y-460202D01*
X-26504Y-445619D01*
Y-463119D01*
G01X-14681D02*
X-15991Y-462827D01*
X-17301Y-461661D01*
X-18175Y-459619D01*
X-18611Y-457286D01*
X-18175Y-454952D01*
X-17301Y-452911D01*
X-15991Y-451744D01*
X-14681Y-451453D01*
X-13371Y-451744D01*
X-12061Y-452911D01*
X-11188Y-454952D01*
X-10969Y-457286D01*
X-11188Y-459619D01*
X-12061Y-461661D01*
X-13371Y-462827D01*
X-14681Y-463119D01*
G01X6749Y-445619D02*
Y-463119D01*
G01Y-460495D02*
X5876Y-461953D01*
X4565Y-462827D01*
X3037Y-463119D01*
X1291Y-462536D01*
X-19Y-461078D01*
X-893Y-459328D01*
X-1111Y-457286D01*
X-893Y-455244D01*
X-19Y-453494D01*
X1291Y-452036D01*
X3037Y-451453D01*
X4565Y-451744D01*
X5657Y-452328D01*
X6749Y-453494D01*
G01X17044Y-455244D02*
X24031D01*
X23376Y-453202D01*
X22284Y-452036D01*
X20756Y-451453D01*
X19227Y-451744D01*
X17917Y-452619D01*
X17044Y-454661D01*
X16607Y-456411D01*
Y-458161D01*
X17044Y-459911D01*
X18136Y-461661D01*
X19446Y-462827D01*
X20974Y-463119D01*
X22502Y-462536D01*
X24031Y-460786D01*
G01X37819Y-463119D02*
Y-445619D01*
G01X1Y-17717D02*
G03X7875Y-25591I7874J0D01*
G01X1Y299252D02*
Y-10394D01*
G01Y-17717D02*
G03X7875Y-25591I7874J0D01*
G01X1Y299252D02*
Y-10394D01*
G01Y-17717D02*
Y-10394D01*
G01D02*
Y-17723D01*
G01X0Y11811D02*
Y0D01*
G01X92520Y299252D02*
X1D01*
G01X92520D02*
X1D01*
G01X0Y318937D02*
G03X11811Y307126I11811J0D01*
G01X0Y968503D02*
Y318937D01*
G01X19685Y988189D02*
G03X0Y968503I0J-19685D01*
G01X43950Y996063D02*
X1D01*
G01X43950D02*
X1D01*
G01Y1008622D02*
Y996063D01*
G01Y1008622D02*
Y996063D01*
G01X15001Y1023622D02*
G03X1Y1008622I0J-15000D01*
G01X15001Y1023622D02*
G03X1Y1008622I0J-15000D01*
G01X7875Y-25591D02*
X45337D01*
G01X7875D02*
X45337D01*
G01X11811Y307126D02*
X100394D01*
G01X10710Y1008622D02*
G03X19292I4291J0D01*
G01D02*
G03X10710I-4291J0D01*
G01X99804Y1023622D02*
X15001D01*
G01X99804D02*
X15001D01*
G01X103740Y988189D02*
X19685D01*
G01X53211Y-25591D02*
G03X45337I-3937J0D01*
G01X53211D02*
G03X45337I-3937J0D01*
G01X53211D02*
G03X45337I-3937J0D01*
G01X53211D02*
G03X45337I-3937J0D01*
G01X43950Y988189D02*
G03Y996063I0J3937D01*
G01Y988189D02*
G03Y996063I0J3937D01*
G01X53211Y-25591D02*
X1392127D01*
G01X53211D02*
X1392127D01*
G01X69147Y996063D02*
G03Y988189I0J-3937D01*
G01Y996063D02*
G03Y988189I0J-3937D01*
G01X99804Y996063D02*
X69147D01*
G01X99804D02*
X69147D01*
G01X94412Y72220D02*
G03X85830Y72219I-4291J-1D01*
G01D02*
G03X94412Y72220I4291J0D01*
G01X100394Y291377D02*
G03X92520Y299252I-7874J1D01*
G01X100394Y291377D02*
G03X92520Y299252I-7874J1D01*
G01X99804Y1023622D02*
Y996063D01*
G01Y1023622D02*
Y996063D01*
G01X100394Y236259D02*
G03X116142Y220511I15748J0D01*
G01D02*
X232088D01*
G01X100394Y236259D02*
G03X116142Y220511I15748J0D01*
G01D02*
X232088D01*
G01X116142Y228385D02*
X239961D01*
G01X108268Y236259D02*
G03X116142Y228385I7874J0D01*
G01X108268Y299252D02*
Y236259D01*
G01X100395Y240899D02*
X100394Y236259D01*
G01X100395Y240899D02*
X100394Y236259D01*
G01X108269Y240899D02*
G03X100395I-3937J0D01*
G01X108269D02*
G03X100395I-3937J0D01*
G01Y266096D02*
G03X108269I3937J-1D01*
G01X100395D02*
G03X108269I3937J-1D01*
G01X100395D02*
X100394Y291377D01*
G01X100395Y266096D02*
X100394Y291377D01*
G01X108268Y299252D02*
G03X100394Y307126I-7874J0D01*
G01X103740Y988189D02*
G03X107677Y992126I0J3937D01*
G01Y1018109D02*
Y992126D01*
G01X136024Y1018109D02*
X136023Y1021653D01*
X134055Y1023622D01*
X109645D01*
X107677Y1021653D01*
Y1018109D01*
G01X136024Y994290D02*
G03X143505I3740J0D01*
G01X136024D02*
Y1018109D01*
G01X143504D02*
Y994290D01*
G01X187598Y1018109D02*
Y1021653D01*
X185630Y1023622D01*
X145472D01*
X143504Y1021653D01*
Y1018109D01*
G01X151575Y220511D02*
X226378D01*
G01X151575D02*
X226378D01*
G01X187598Y992126D02*
Y1018109D01*
G01Y992126D02*
G03X191535Y988189I3937J0D01*
G01X261220D02*
X191535D01*
G01X212681Y996063D02*
X195473D01*
G01D02*
Y1023622D01*
G01X212681Y996063D02*
X195473D01*
G01D02*
Y1023622D01*
G01D02*
X257284D01*
G01X195473D02*
X257284D01*
G01X212681Y988189D02*
G03Y996063I0J3937D01*
G01Y988189D02*
G03Y996063I0J3937D01*
G01X222751Y1008622D02*
G03X231333I4291J0D01*
G01D02*
G03X222751I-4291J0D01*
G01X243898Y70866D02*
G03X247835Y66928I3937J-1D01*
G01X243898Y224448D02*
Y70866D01*
G01X236025Y164487D02*
Y70866D01*
G01D02*
G03X247836Y59055I11811J0D01*
G01X236025Y164487D02*
Y70866D01*
G01D02*
G03X247836Y59055I11811J0D01*
G01X243899Y164487D02*
G03X236025I-3937J0D01*
G01X243899D02*
G03X236025I-3937J0D01*
G01Y189684D02*
G03X243899I3937J0D01*
G01X236025D02*
G03X243899I3937J0D01*
G01X236025D02*
Y216574D01*
G01Y189684D02*
Y216574D01*
G01D02*
G03X232088Y220511I-3937J0D01*
G01X236025Y216574D02*
G03X232088Y220511I-3937J0D01*
G01X243898Y224448D02*
G03X239961Y228385I-3937J0D01*
G01X237877Y996063D02*
G03Y988189I0J-3937D01*
G01Y996063D02*
G03Y988189I0J-3937D01*
G01X257284Y996063D02*
X237877D01*
G01X257284D02*
X237877D01*
G01X247835Y66929D02*
X289174D01*
G01X247836Y59055D02*
X285237D01*
G01X247836D02*
X285237D01*
G01X261220Y988189D02*
G03X265157Y992126I0J3937D01*
G01X257284Y1023622D02*
Y996063D01*
G01Y1023622D02*
Y996063D01*
G01X281019Y-508119D02*
Y-490619D01*
X278399Y-494119D01*
G01Y-508119D02*
X283639D01*
G01X293716Y-504619D02*
X295025Y-506661D01*
X296772Y-507827D01*
X298737Y-508119D01*
X300484Y-507827D01*
X302231Y-506369D01*
X303322Y-504619D01*
X303541Y-502869D01*
X303104Y-500828D01*
X301576Y-499369D01*
X300047Y-498786D01*
X298082D01*
G01X300047D02*
X301357Y-497911D01*
X302449Y-496453D01*
X302886Y-494703D01*
X302449Y-492952D01*
X301357Y-491494D01*
X299392Y-490619D01*
X297427Y-490911D01*
X295462Y-492078D01*
G01X312307Y-506078D02*
X313836Y-507536D01*
X315582Y-508119D01*
X317329Y-507536D01*
X318857Y-505786D01*
X319949Y-503161D01*
X320386Y-500536D01*
Y-497328D01*
X319949Y-494703D01*
X318857Y-492369D01*
X317547Y-491202D01*
X316019Y-490619D01*
X314272Y-491202D01*
X312962Y-492369D01*
X312089Y-494119D01*
X311652Y-496453D01*
X312089Y-498494D01*
X313181Y-500536D01*
X314491Y-501703D01*
X316019Y-501994D01*
X317765Y-501411D01*
X319076Y-499952D01*
X320386Y-497328D01*
G01X336139Y-508119D02*
Y-490619D01*
X328060Y-503161D01*
X338978D01*
G01X351019Y-508119D02*
X352547Y-507827D01*
X354294Y-506953D01*
X355386Y-505495D01*
X355822Y-503452D01*
X355386Y-501411D01*
X354076Y-499661D01*
X352111Y-498786D01*
X349927D01*
X348617Y-498202D01*
X347525Y-496744D01*
X347089Y-494703D01*
X347744Y-492661D01*
X349272Y-491202D01*
X351019Y-490619D01*
X352765Y-491202D01*
X354294Y-492661D01*
X354949Y-494703D01*
X354512Y-496744D01*
X353421Y-498202D01*
X352111Y-498786D01*
X349927D01*
X347962Y-499661D01*
X346652Y-501411D01*
X346216Y-503452D01*
X346652Y-505495D01*
X347744Y-506953D01*
X349491Y-507827D01*
X351019Y-508119D01*
G01X267902Y-463119D02*
Y-445619D01*
X273142D01*
X274889Y-446494D01*
X276199Y-448536D01*
X276636Y-450869D01*
X276199Y-453202D01*
X275107Y-454952D01*
X273142Y-455828D01*
X267902D01*
G01X294572Y-447078D02*
X293262Y-446202D01*
X291734Y-445619D01*
X289987D01*
X288022Y-446494D01*
X286494Y-447952D01*
X285402Y-449703D01*
X284529Y-452619D01*
X284310Y-455244D01*
X284747Y-457869D01*
X285402Y-459619D01*
X286712Y-461369D01*
X288241Y-462536D01*
X289769Y-463119D01*
X291297D01*
X292826Y-462536D01*
X294136Y-461661D01*
X295228Y-460495D01*
G01X309015Y-453786D02*
X309889Y-452911D01*
X310544Y-451453D01*
X310981Y-449410D01*
X310544Y-447661D01*
X309671Y-446494D01*
X308142Y-445619D01*
X302247D01*
Y-463119D01*
X309452D01*
X310981Y-461953D01*
X311854Y-460202D01*
X312291Y-458161D01*
X311854Y-456119D01*
X310544Y-454369D01*
X309015Y-453786D01*
X302247D01*
G01X318219Y-468952D02*
X331319D01*
G01X337247Y-463119D02*
Y-445619D01*
X347291Y-463119D01*
Y-445619D01*
G01X359769Y-463119D02*
X358022Y-462827D01*
X356494Y-461661D01*
X355184Y-459911D01*
X354310Y-457869D01*
X353874Y-455536D01*
Y-453202D01*
X354310Y-450869D01*
X355184Y-448827D01*
X356494Y-447078D01*
X358022Y-445911D01*
X359769Y-445619D01*
X361515Y-445911D01*
X363044Y-447078D01*
X364354Y-448827D01*
X365228Y-450869D01*
X365664Y-453202D01*
Y-455536D01*
X365228Y-457869D01*
X364354Y-459911D01*
X363044Y-461661D01*
X361515Y-462827D01*
X359769Y-463119D01*
G01X265157Y1018109D02*
Y992126D01*
G01X545472Y1018109D02*
Y1021653D01*
X543504Y1023622D01*
X267126D01*
X265157Y1021653D01*
Y1018109D01*
G01X293111Y3937D02*
G03X297047Y0I3937J0D01*
G01X293110Y62992D02*
Y3937D01*
G01X285237D02*
G03X297048Y-7874I11811J0D01*
G01X285237Y59055D02*
Y3937D01*
G01D02*
G03X297048Y-7874I11811J0D01*
G01X285237Y59055D02*
Y3937D01*
G01X293111Y62992D02*
G03X289174Y66929I-3937J0D01*
G01X297047Y0D02*
X1108209D01*
G01X297037Y-7874D02*
X301187D01*
G01D02*
G03Y0I0J3937D01*
G01X297037Y-7874D02*
X301187D01*
G01D02*
G03Y0I0J3937D01*
G01X318510Y-7874D02*
X515333D01*
G01X318510Y0D02*
G03Y-7874I0J-3937D01*
G01D02*
X515333D01*
G01X318510Y0D02*
G03Y-7874I0J-3937D01*
G01X410610Y-445619D02*
X416069Y-463119D01*
X421528Y-445619D01*
G01X437936Y-463119D02*
X429202D01*
Y-445619D01*
X437936D01*
G01X434442Y-454077D02*
X429202D01*
G01X446702Y-463119D02*
Y-445619D01*
X452161D01*
X453907Y-446494D01*
X454999Y-447661D01*
X455436Y-449994D01*
X454999Y-452328D01*
X453689Y-453786D01*
X452161Y-454661D01*
X446702D01*
G01X452161D02*
X455436Y-463119D01*
G01X468569Y-463702D02*
X468132Y-463411D01*
Y-462827D01*
X468569Y-462536D01*
X469006Y-462827D01*
Y-463411D01*
X468569Y-463702D01*
G01X433569Y-508119D02*
Y-490619D01*
X430949Y-494119D01*
G01Y-508119D02*
X436189D01*
G01X452815Y-498786D02*
X453689Y-497911D01*
X454344Y-496453D01*
X454781Y-494410D01*
X454344Y-492661D01*
X453471Y-491494D01*
X451942Y-490619D01*
X446047D01*
Y-508119D01*
X453252D01*
X454781Y-506953D01*
X455654Y-505202D01*
X456091Y-503161D01*
X455654Y-501119D01*
X454344Y-499369D01*
X452815Y-498786D01*
X446047D01*
G01X515302Y-7874D02*
G03Y0I0J3937D01*
G01Y-7874D02*
G03Y0I0J3937D01*
G01X543716Y-508119D02*
Y-490619D01*
X548082D01*
X549829Y-491494D01*
X551139Y-492661D01*
X552231Y-494410D01*
X553104Y-496453D01*
X553322Y-499369D01*
X553104Y-502286D01*
X552231Y-504328D01*
X551139Y-506078D01*
X549829Y-507244D01*
X548082Y-508119D01*
X543716D01*
G01X561652D02*
Y-490619D01*
X567111D01*
X568857Y-491494D01*
X569949Y-492661D01*
X570386Y-494994D01*
X569949Y-497328D01*
X568639Y-498786D01*
X567111Y-499661D01*
X561652D01*
G01X567111D02*
X570386Y-508119D01*
G01X580899Y-490619D02*
X586139D01*
G01X583519D02*
Y-508119D01*
G01X580899D02*
X586139D01*
G01X596652Y-490619D02*
Y-508119D01*
X605386D01*
G01X614152Y-490619D02*
Y-508119D01*
X622886D01*
G01X544152Y-445619D02*
Y-463119D01*
X552886D01*
G01X569949D02*
Y-451453D01*
G01Y-453494D02*
X569076Y-452328D01*
X567765Y-451744D01*
X566237Y-451453D01*
X564709Y-452036D01*
X563399Y-453202D01*
X562525Y-454952D01*
X562089Y-457286D01*
X562525Y-459619D01*
X563399Y-461369D01*
X564709Y-462536D01*
X566237Y-463119D01*
X567765Y-462827D01*
X569076Y-461953D01*
X569949Y-460786D01*
G01X578934Y-468369D02*
X580244Y-468952D01*
X581991Y-468369D01*
X583082Y-467203D01*
X583956Y-465744D01*
X585265Y-461078D01*
X588104Y-451453D01*
G01X581117D02*
X585265Y-461078D01*
G01X597744Y-455244D02*
X604731D01*
X604076Y-453202D01*
X602984Y-452036D01*
X601456Y-451453D01*
X599927Y-451744D01*
X598617Y-452619D01*
X597744Y-454661D01*
X597307Y-456411D01*
Y-458161D01*
X597744Y-459911D01*
X598836Y-461661D01*
X600146Y-462827D01*
X601674Y-463119D01*
X603202Y-462536D01*
X604731Y-460786D01*
G01X615462Y-463119D02*
Y-451453D01*
G01Y-453786D02*
X616554Y-452619D01*
X617646Y-451744D01*
X619174Y-451453D01*
X620265Y-451744D01*
X621576Y-452619D01*
G01X540499Y-7874D02*
X727049D01*
G01X540499Y0D02*
G03Y-7874I0J-3937D01*
G01D02*
X727049D01*
G01X540499Y0D02*
G03Y-7874I0J-3937D01*
G01X545472Y994290D02*
G03X552953I3740J1D01*
G01X545472D02*
Y1018109D01*
G01X552953D02*
Y994290D01*
G01X597047Y1018109D02*
Y1021653D01*
X595078Y1023622D01*
X554921D01*
X552952Y1021653D01*
X552953Y1018109D01*
G01X597047Y992126D02*
Y1018109D01*
G01X597048Y992126D02*
G03X600984Y988189I3937J0D01*
G01X713189D02*
X600984D01*
G01X641198Y996063D02*
X604922D01*
G01D02*
Y1023622D01*
G01X641198Y996063D02*
X604922D01*
G01D02*
Y1023622D01*
G01D02*
X709253D01*
G01X604922D02*
X709253D01*
G01X641198Y988189D02*
G03Y996063I0J3937D01*
G01Y988189D02*
G03Y996063I0J3937D01*
G01X649684Y1008622D02*
G03X658266I4291J0D01*
G01D02*
G03X649684I-4291J0D01*
G01X666395Y996063D02*
G03Y988189I0J-3937D01*
G01Y996063D02*
G03Y988189I0J-3937D01*
G01X709253Y996063D02*
X666395D01*
G01X709253D02*
X666395D01*
G01X686702Y-490619D02*
Y-508119D01*
X695436D01*
G01X703984Y-513369D02*
X705294Y-513952D01*
X707041Y-513369D01*
X708132Y-512203D01*
X709006Y-510744D01*
X710315Y-506078D01*
X713154Y-496453D01*
G01X706167D02*
X710315Y-506078D01*
G01X722357Y-508119D02*
Y-496453D01*
G01Y-499369D02*
X723231Y-497911D01*
X724541Y-496744D01*
X726287Y-496453D01*
X727815Y-496744D01*
X729126Y-497911D01*
X729781Y-499952D01*
Y-508119D01*
G01X739857D02*
Y-496453D01*
G01Y-499369D02*
X740731Y-497911D01*
X742041Y-496744D01*
X743787Y-496453D01*
X745315Y-496744D01*
X746626Y-497911D01*
X747281Y-499952D01*
Y-508119D01*
G01X774202Y-490619D02*
Y-508119D01*
X782936D01*
G01X796069Y-496453D02*
Y-508119D01*
G01Y-491786D02*
X795632Y-491494D01*
Y-490911D01*
X796069Y-490619D01*
X796506Y-490911D01*
Y-491494D01*
X796069Y-491786D01*
G01X809857Y-496453D02*
Y-504619D01*
X810731Y-506661D01*
X812041Y-507827D01*
X813569Y-508119D01*
X815097Y-507827D01*
X816407Y-506661D01*
X817281Y-504619D01*
G01Y-508119D02*
Y-496453D01*
G01X686266Y-463119D02*
Y-445619D01*
X690632D01*
X692379Y-446494D01*
X693689Y-447661D01*
X694781Y-449410D01*
X695654Y-451453D01*
X695872Y-454369D01*
X695654Y-457286D01*
X694781Y-459328D01*
X693689Y-461078D01*
X692379Y-462244D01*
X690632Y-463119D01*
X686266D01*
G01X705294Y-455244D02*
X712281D01*
X711626Y-453202D01*
X710534Y-452036D01*
X709006Y-451453D01*
X707477Y-451744D01*
X706167Y-452619D01*
X705294Y-454661D01*
X704857Y-456411D01*
Y-458161D01*
X705294Y-459911D01*
X706386Y-461661D01*
X707696Y-462827D01*
X709224Y-463119D01*
X710752Y-462536D01*
X712281Y-460786D01*
G01X722794Y-461078D02*
X723886Y-462244D01*
X725414Y-463119D01*
X726724D01*
X728034Y-462536D01*
X728907Y-461661D01*
X729344Y-460495D01*
X729126Y-458744D01*
X728252Y-457869D01*
X724322Y-456119D01*
X723449Y-454077D01*
X723886Y-452619D01*
X724759Y-451744D01*
X726069Y-451453D01*
X727379Y-451744D01*
X728689Y-452619D01*
G01X743569Y-451453D02*
Y-463119D01*
G01Y-446786D02*
X743132Y-446494D01*
Y-445911D01*
X743569Y-445619D01*
X744006Y-445911D01*
Y-446494D01*
X743569Y-446786D01*
G01X758012Y-467494D02*
X759541Y-468661D01*
X761287Y-468952D01*
X762815Y-468661D01*
X764126Y-467203D01*
X764999Y-465161D01*
Y-451453D01*
G01Y-453786D02*
X764126Y-452619D01*
X762815Y-451744D01*
X761287Y-451453D01*
X759541Y-452036D01*
X758449Y-453202D01*
X757575Y-455244D01*
X757139Y-457286D01*
X757357Y-459036D01*
X758231Y-461078D01*
X759541Y-462536D01*
X761287Y-463119D01*
X762597Y-462827D01*
X764126Y-461661D01*
X764999Y-460495D01*
G01X774857Y-463119D02*
Y-451453D01*
G01Y-454369D02*
X775731Y-452911D01*
X777041Y-451744D01*
X778787Y-451453D01*
X780315Y-451744D01*
X781626Y-452911D01*
X782281Y-454952D01*
Y-463119D01*
G01X792794Y-455244D02*
X799781D01*
X799126Y-453202D01*
X798034Y-452036D01*
X796506Y-451453D01*
X794977Y-451744D01*
X793667Y-452619D01*
X792794Y-454661D01*
X792357Y-456411D01*
Y-458161D01*
X792794Y-459911D01*
X793886Y-461661D01*
X795196Y-462827D01*
X796724Y-463119D01*
X798252Y-462536D01*
X799781Y-460786D01*
G01X810512Y-463119D02*
Y-451453D01*
G01Y-453786D02*
X811604Y-452619D01*
X812696Y-451744D01*
X814224Y-451453D01*
X815315Y-451744D01*
X816626Y-452619D01*
G01X713189Y988189D02*
G03X717126Y992126I0J3937D01*
G01Y1018109D02*
Y992126D01*
G01X709253Y1023622D02*
Y996063D01*
G01Y1023622D02*
Y996063D01*
G01X745472Y1018109D02*
Y1021653D01*
X743504Y1023622D01*
X719094D01*
X717126Y1021653D01*
Y1018109D01*
G01X727049Y-7874D02*
G03Y0I0J3937D01*
G01Y-7874D02*
G03Y0I0J3937D01*
G01X752246Y-7874D02*
X984201D01*
G01X752246Y0D02*
G03Y-7874I0J-3937D01*
G01D02*
X984201D01*
G01X752246Y0D02*
G03Y-7874I0J-3937D01*
G01X745472Y994290D02*
G03X752953I3741J1D01*
G01X745472D02*
Y1018109D01*
G01X752953D02*
Y994290D01*
G01X797047Y1018109D02*
Y1021653D01*
X795078Y1023622D01*
X754921D01*
X752952Y1021653D01*
X752953Y1018109D01*
G01X797047Y992126D02*
Y1018109D01*
G01X797048Y992126D02*
G03X800984Y988189I3937J0D01*
G01X902165D02*
X800984D01*
G01X859109Y996063D02*
X804922D01*
G01D02*
Y1023622D01*
G01X859109Y996063D02*
X804922D01*
G01D02*
Y1023622D01*
G01D02*
X1325399D01*
G01X804922D02*
X1325399D01*
G01X857269Y-508119D02*
Y-490619D01*
X854649Y-494119D01*
G01Y-508119D02*
X859889D01*
G01X874769D02*
Y-490619D01*
X872149Y-494119D01*
G01Y-508119D02*
X877389D01*
G01X888339Y-508702D02*
X896199Y-490619D01*
G01X909769Y-508119D02*
Y-490619D01*
X907149Y-494119D01*
G01Y-508119D02*
X912389D01*
G01X922466Y-504619D02*
X923775Y-506661D01*
X925522Y-507827D01*
X927487Y-508119D01*
X929234Y-507827D01*
X930981Y-506369D01*
X932072Y-504619D01*
X932291Y-502869D01*
X931854Y-500828D01*
X930326Y-499369D01*
X928797Y-498786D01*
X926832D01*
G01X928797D02*
X930107Y-497911D01*
X931199Y-496453D01*
X931636Y-494703D01*
X931199Y-492952D01*
X930107Y-491494D01*
X928142Y-490619D01*
X926177Y-490911D01*
X924212Y-492078D01*
G01X940839Y-508702D02*
X948699Y-490619D01*
G01X958121Y-493536D02*
X959431Y-491786D01*
X960959Y-490911D01*
X962706Y-490619D01*
X964889Y-491202D01*
X966417Y-492661D01*
X966854Y-494410D01*
X966636Y-496161D01*
X965762Y-497619D01*
X961396Y-500536D01*
X959431Y-502577D01*
X958121Y-505495D01*
X957684Y-508119D01*
X966854D01*
G01X979769Y-490619D02*
X978022Y-491202D01*
X976712Y-492661D01*
X975839Y-494410D01*
X975184Y-496744D01*
X974966Y-499369D01*
X975184Y-501994D01*
X975839Y-504328D01*
X976712Y-506078D01*
X978022Y-507536D01*
X979769Y-508119D01*
X981515Y-507536D01*
X982826Y-506078D01*
X983699Y-504328D01*
X984354Y-501994D01*
X984572Y-499369D01*
X984354Y-496744D01*
X983699Y-494410D01*
X982826Y-492661D01*
X981515Y-491202D01*
X979769Y-490619D01*
G01X997269Y-508119D02*
Y-490619D01*
X994649Y-494119D01*
G01Y-508119D02*
X999889D01*
G01X1017389D02*
Y-490619D01*
X1009310Y-503161D01*
X1020228D01*
G01X859109Y988189D02*
G03Y996063I0J3937D01*
G01Y988189D02*
G03Y996063I0J3937D01*
G01X884306D02*
G03Y988189I0J-3937D01*
G01Y996063D02*
G03Y988189I0J-3937D01*
G01X902166Y996063D02*
X884306D01*
G01X902166D02*
X884306D01*
G01X904966Y-463119D02*
Y-445619D01*
X909332D01*
X911079Y-446494D01*
X912389Y-447661D01*
X913481Y-449410D01*
X914354Y-451453D01*
X914572Y-454369D01*
X914354Y-457286D01*
X913481Y-459328D01*
X912389Y-461078D01*
X911079Y-462244D01*
X909332Y-463119D01*
X904966D01*
G01X931199D02*
Y-451453D01*
G01Y-453494D02*
X930326Y-452328D01*
X929015Y-451744D01*
X927487Y-451453D01*
X925959Y-452036D01*
X924649Y-453202D01*
X923775Y-454952D01*
X923339Y-457286D01*
X923775Y-459619D01*
X924649Y-461369D01*
X925959Y-462536D01*
X927487Y-463119D01*
X929015Y-462827D01*
X930326Y-461953D01*
X931199Y-460786D01*
G01X944769Y-445619D02*
Y-463119D01*
G01X941712Y-451453D02*
X947826D01*
G01X958994Y-455244D02*
X965981D01*
X965326Y-453202D01*
X964234Y-452036D01*
X962706Y-451453D01*
X961177Y-451744D01*
X959867Y-452619D01*
X958994Y-454661D01*
X958557Y-456411D01*
Y-458161D01*
X958994Y-459911D01*
X960086Y-461661D01*
X961396Y-462827D01*
X962924Y-463119D01*
X964452Y-462536D01*
X965981Y-460786D01*
G01X921850Y968503D02*
G03X902165Y988189I-19685J1D01*
G01X929725Y968504D02*
G03X902166Y996063I-27559J0D01*
G01D02*
X902195D01*
G01X929725Y968504D02*
G03X902166Y996063I-27559J0D01*
G01D02*
X902195D01*
G01X921850Y775590D02*
Y968503D01*
G01Y775590D02*
G03X925787Y771653I3937J0D01*
G01X984843D02*
X925787D01*
G01X929725Y779527D02*
Y886881D01*
G01Y779527D02*
X980906D01*
G01X929725D02*
Y886881D01*
G01Y779527D02*
X980906D01*
G01X929725Y886881D02*
G03X921851I-3937J1D01*
G01X929725D02*
G03X921851I-3937J1D01*
G01Y912079D02*
G03X929725I3937J-1D01*
G01X921851D02*
G03X929725I3937J-1D01*
G01Y912078D02*
Y968504D01*
G01Y912078D02*
Y968504D01*
G01X959606Y850829D02*
G03X951024I-4291J0D01*
G01D02*
G03X959606I4291J0D01*
G01X984201Y-7874D02*
G03Y0I0J3937D01*
G01Y-7874D02*
G03Y0I0J3937D01*
G01X984843Y771653D02*
G03X988780Y775590I0J3937D01*
G01X980907Y886881D02*
X980906Y779527D01*
G01X980907Y886881D02*
X980906Y779527D01*
G01X988781Y886881D02*
G03X980907I-3937J1D01*
G01X988781D02*
G03X980907I-3937J1D01*
G01Y912079D02*
G03X988781I3937J-1D01*
G01X980907D02*
G03X988781I3937J-1D01*
G01X980907D02*
X980906Y968504D01*
G01X980907Y912079D02*
X980906Y968504D01*
G01X1008465Y996063D02*
G03X980906Y968504I0J-27559D01*
G01X1008465Y996063D02*
G03X980906Y968504I0J-27559D01*
G01X1005118Y237794D02*
X1011418D01*
G03Y250394I0J6300D01*
G01X1005118D01*
G03Y237794I0J-6300D01*
G01Y405117D02*
X1011418D01*
G03Y417717I0J6300D01*
G01X1005118D01*
G03Y405117I0J-6300D01*
G01X988780Y968503D02*
Y775590D01*
G01X1008465Y988189D02*
G03X988780Y968503I0J-19685D01*
G01X1009398Y-7874D02*
X1108229D01*
G01X1009398Y0D02*
G03Y-7874I-1J-3937D01*
G01D02*
X1108229D01*
G01X1009398Y0D02*
G03Y-7874I-1J-3937D01*
G01X1008218Y237744D02*
X1008168Y232044D01*
G01X1009674Y232731D02*
X1008218Y237744D01*
X1006674Y232757D01*
X1009674Y232731D01*
G01X1008218Y405067D02*
X1008168Y399367D01*
G01X1009674Y400054D02*
X1008218Y405067D01*
X1006674Y400080D01*
X1009674Y400054D01*
G01X1380315Y988189D02*
X1008465D01*
G01X1070592Y996063D02*
X1008466D01*
G01X1070592D02*
X1008466D01*
G01X1070592Y988189D02*
G03Y996063I0J3937D01*
G01Y988189D02*
G03Y996063I0J3937D01*
G01X1095789D02*
G03Y988189I0J-3937D01*
G01Y996063D02*
G03Y988189I0J-3937D01*
G01X1325399Y996063D02*
X1095789D01*
G01X1325399D02*
X1095789D01*
G01X1112146Y3937D02*
Y210629D01*
G01X1108209Y0D02*
G03X1112146Y3937I0J3937D01*
G01X1108208Y-7874D02*
G03X1120020Y3938I1J11811D01*
G01X1108208Y-7874D02*
G03X1120020Y3938I1J11811D01*
G01Y99950D02*
G03X1112146I-3937J0D01*
G01X1120020D02*
G03X1112146I-3937J0D01*
G01Y125147D02*
G03X1120020I3937J0D01*
G01X1112146D02*
G03X1120020I3937J0D01*
G01X1116083Y214566D02*
X1194824D01*
G01X1116083D02*
G03X1112146Y210629I0J-3937D01*
G01X1120020Y99950D02*
Y3938D01*
G01Y99950D02*
Y3938D01*
G01Y125147D02*
Y206693D01*
G01Y125147D02*
Y206693D01*
G01X1120021D02*
X1190887D01*
G01X1120021D02*
X1190887D01*
G01X1161386Y128841D02*
G03X1152804I-4291J0D01*
G01D02*
G03X1161386I4291J0D01*
G01X1198760Y3937D02*
G03X1210571Y-7874I11811J0D01*
G01X1198760Y3937D02*
G03X1210571Y-7874I11811J0D01*
G01X1198761Y97100D02*
X1198760Y3937D01*
G01X1198761Y97100D02*
X1198760Y3937D01*
G01X1206635Y97100D02*
G03X1198761I-3937J0D01*
G01X1206635D02*
G03X1198761I-3937J0D01*
G01Y122297D02*
G03X1206635I3937J0D01*
G01X1198761D02*
G03X1206635I3937J0D01*
G01X1198761D02*
Y168002D01*
G01Y122297D02*
Y168002D01*
G01X1190887Y179134D02*
G03X1198761Y167998I11811J0D01*
G01X1190887Y179134D02*
G03X1198761Y167998I11811J0D01*
G01X1198760Y179133D02*
G03X1202697Y175196I3937J0D01*
G01X1198760Y210629D02*
Y179133D01*
G01X1190887Y206693D02*
Y179134D01*
G01Y206693D02*
Y179134D01*
G01X1198760Y210629D02*
G03X1194824Y214566I-3937J0D01*
G01X1210571Y0D02*
X1396063D01*
G01X1206634Y3937D02*
G03X1210571Y0I3937J0D01*
G01X1206634Y171259D02*
Y3937D01*
G01X1210552Y-7874D02*
X1210572D01*
G01D02*
G03Y0I0J3937D01*
G01X1210552Y-7874D02*
X1210572D01*
G01D02*
G03Y0I0J3937D01*
G01X1206634Y171259D02*
G03X1202697Y175196I-3937J0D01*
G01X1226320Y-7874D02*
X1380317D01*
G01X1226320Y0D02*
G03Y-7874I0J-3937D01*
G01D02*
X1380317D01*
G01X1226320Y0D02*
G03Y-7874I0J-3937D01*
G01X1227116Y149161D02*
X1227066Y143461D01*
G01X1228572Y144148D02*
X1227116Y149161D01*
X1225572Y144174D01*
X1228572Y144148D01*
G01X1224016Y149211D02*
X1230316D01*
G03Y161811I0J6300D01*
G01X1224016D01*
G03Y149211I0J-6300D01*
G01X1227115Y405067D02*
X1227065Y399367D01*
G01X1228571Y400054D02*
X1227115Y405067D01*
X1225571Y400080D01*
X1228571Y400054D01*
G01X1224015Y405117D02*
X1230315D01*
G03Y417717I0J6300D01*
G01X1224015D01*
G03Y405117I0J-6300D01*
G01X1354801Y996063D02*
X1325399D01*
G01X1354801D02*
X1325399D01*
G01Y1023622D02*
X1385001D01*
G01X1325399D02*
X1385001D01*
G01X1354801Y988189D02*
G03Y996063I0J3937D01*
G01Y988189D02*
G03Y996063I0J3937D01*
G01X1380316Y-7874D02*
G03Y0I0J3937D01*
G01Y-7874D02*
G03Y0I0J3937D01*
G01X1400000Y968503D02*
G03X1380315Y988189I-19685J1D01*
G01X1379998Y996063D02*
G03Y988189I0J-3937D01*
G01Y996063D02*
G03Y988189I0J-3937D01*
G01X1400001Y996063D02*
X1379998D01*
G01X1400001D02*
X1379998D01*
G01X1392127Y-25591D02*
G03X1400001Y-17717I0J7874D01*
G01X1392167Y-15015D02*
G03X1383585I-4291J0D01*
G01D02*
G03X1392167I4291J0D01*
G01X1392127Y-25591D02*
G03X1400001Y-17717I0J7874D01*
G01X1396063Y0D02*
G03X1400000Y3937I0J3937D01*
G01X1396064Y-7874D02*
X1400001D01*
G01X1396064Y0D02*
G03Y-7874I0J-3937D01*
G01D02*
X1400001D01*
G01X1396064Y0D02*
G03Y-7874I0J-3937D01*
G01X1380710Y1008622D02*
G03X1389292I4291J0D01*
G01D02*
G03X1380710I-4291J0D01*
G01X1400001D02*
G03X1385001Y1023622I-15000J0D01*
G01X1400001Y1008622D02*
G03X1385001Y1023622I-15000J0D01*
G01X1400001Y-17717D02*
Y-7874D01*
G01Y-17717D02*
Y-7874D01*
G01X1400000Y3937D02*
Y968503D01*
G01X1400001Y996063D02*
Y1008622D01*
G01Y996063D02*
Y1008622D01*
G01X1740585Y31400D02*
Y43900D01*
X1747715Y31400D01*
Y43900D01*
G01X1756550Y31400D02*
X1755620Y31608D01*
X1754690Y32441D01*
X1754070Y33900D01*
X1753760Y35567D01*
X1754070Y37233D01*
X1754690Y38692D01*
X1755620Y39525D01*
X1756550Y39733D01*
X1757480Y39525D01*
X1758410Y38692D01*
X1759030Y37233D01*
X1759185Y35567D01*
X1759030Y33900D01*
X1758410Y32441D01*
X1757480Y31608D01*
X1756550Y31400D01*
G01X1768950Y43900D02*
Y31400D01*
G01X1766780Y39733D02*
X1771120D01*
G01X1779025Y37025D02*
X1783985D01*
X1783520Y38483D01*
X1782745Y39317D01*
X1781660Y39733D01*
X1780575Y39525D01*
X1779645Y38900D01*
X1779025Y37442D01*
X1778715Y36191D01*
Y34942D01*
X1779025Y33692D01*
X1779800Y32441D01*
X1780730Y31608D01*
X1781815Y31400D01*
X1782900Y31817D01*
X1783985Y33066D01*
G01X1793750Y30983D02*
X1793440Y31192D01*
Y31608D01*
X1793750Y31817D01*
X1794060Y31608D01*
Y31192D01*
X1793750Y30983D01*
G01Y36608D02*
X1793440Y36817D01*
Y37233D01*
X1793750Y37442D01*
X1794060Y37233D01*
Y36817D01*
X1793750Y36608D01*
G01X1803050Y31400D02*
Y43900D01*
X1806925D01*
X1808165Y43275D01*
X1808940Y42442D01*
X1809250Y40775D01*
X1808940Y39108D01*
X1808010Y38067D01*
X1806925Y37442D01*
X1803050D01*
G01X1806925D02*
X1809250Y31400D01*
G01X1816225Y37025D02*
X1821185D01*
X1820720Y38483D01*
X1819945Y39317D01*
X1818860Y39733D01*
X1817775Y39525D01*
X1816845Y38900D01*
X1816225Y37442D01*
X1815915Y36191D01*
Y34942D01*
X1816225Y33692D01*
X1817000Y32441D01*
X1817930Y31608D01*
X1819015Y31400D01*
X1820100Y31817D01*
X1821185Y33066D01*
G01X1830020Y31400D02*
Y42025D01*
X1830330Y43066D01*
X1830950Y43692D01*
X1831880Y43900D01*
X1832810Y43483D01*
X1833275Y42442D01*
G01X1831415Y38900D02*
X1828315D01*
G01X1841025Y37025D02*
X1845985D01*
X1845520Y38483D01*
X1844745Y39317D01*
X1843660Y39733D01*
X1842575Y39525D01*
X1841645Y38900D01*
X1841025Y37442D01*
X1840715Y36191D01*
Y34942D01*
X1841025Y33692D01*
X1841800Y32441D01*
X1842730Y31608D01*
X1843815Y31400D01*
X1844900Y31817D01*
X1845985Y33066D01*
G01X1853580Y31400D02*
Y39733D01*
G01Y38067D02*
X1854355Y38900D01*
X1855130Y39525D01*
X1856215Y39733D01*
X1856990Y39525D01*
X1857920Y38900D01*
G01X1880550Y43900D02*
Y31400D01*
G01X1878380Y39733D02*
X1882720D01*
G01X1892950Y31400D02*
X1892020Y31608D01*
X1891090Y32441D01*
X1890470Y33900D01*
X1890160Y35567D01*
X1890470Y37233D01*
X1891090Y38692D01*
X1892020Y39525D01*
X1892950Y39733D01*
X1893880Y39525D01*
X1894810Y38692D01*
X1895430Y37233D01*
X1895585Y35567D01*
X1895430Y33900D01*
X1894810Y32441D01*
X1893880Y31608D01*
X1892950Y31400D01*
G01X1914340D02*
Y43900D01*
X1917440D01*
X1918680Y43275D01*
X1919610Y42442D01*
X1920385Y41192D01*
X1921005Y39733D01*
X1921160Y37650D01*
X1921005Y35567D01*
X1920385Y34108D01*
X1919610Y32858D01*
X1918680Y32025D01*
X1917440Y31400D01*
X1914340D01*
G01X1927050D02*
Y43900D01*
X1930925D01*
X1932165Y43275D01*
X1932940Y42442D01*
X1933250Y40775D01*
X1932940Y39108D01*
X1932010Y38067D01*
X1930925Y37442D01*
X1927050D01*
G01X1930925D02*
X1933250Y31400D01*
G01X1940690Y43900D02*
X1944410D01*
G01X1942550D02*
Y31400D01*
G01X1940690D02*
X1944410D01*
G01X1951850Y43900D02*
Y31400D01*
X1958050D01*
G01X1964250Y43900D02*
Y31400D01*
X1970450D01*
G01X1992150D02*
Y43900D01*
G01X2007340Y31400D02*
Y39733D01*
G01Y38275D02*
X2006720Y39108D01*
X2005790Y39525D01*
X2004705Y39733D01*
X2003620Y39317D01*
X2002690Y38483D01*
X2002070Y37233D01*
X2001760Y35567D01*
X2002070Y33900D01*
X2002690Y32650D01*
X2003620Y31817D01*
X2004705Y31400D01*
X2005790Y31608D01*
X2006720Y32233D01*
X2007340Y33066D01*
G01X2013695Y27650D02*
X2014625Y27233D01*
X2015865Y27650D01*
X2016640Y28483D01*
X2017260Y29525D01*
X2018190Y32858D01*
X2020205Y39733D01*
G01X2015245D02*
X2018190Y32858D01*
G01X2027025Y37025D02*
X2031985D01*
X2031520Y38483D01*
X2030745Y39317D01*
X2029660Y39733D01*
X2028575Y39525D01*
X2027645Y38900D01*
X2027025Y37442D01*
X2026715Y36191D01*
Y34942D01*
X2027025Y33692D01*
X2027800Y32441D01*
X2028730Y31608D01*
X2029815Y31400D01*
X2030900Y31817D01*
X2031985Y33066D01*
G01X2039580Y31400D02*
Y39733D01*
G01Y38067D02*
X2040355Y38900D01*
X2041130Y39525D01*
X2042215Y39733D01*
X2042990Y39525D01*
X2043920Y38900D01*
G01X2065620Y31400D02*
Y42025D01*
X2065930Y43066D01*
X2066550Y43692D01*
X2067480Y43900D01*
X2068410Y43483D01*
X2068875Y42442D01*
G01X2067015Y38900D02*
X2063915D01*
G01X2078950Y31400D02*
X2078020Y31608D01*
X2077090Y32441D01*
X2076470Y33900D01*
X2076160Y35567D01*
X2076470Y37233D01*
X2077090Y38692D01*
X2078020Y39525D01*
X2078950Y39733D01*
X2079880Y39525D01*
X2080810Y38692D01*
X2081430Y37233D01*
X2081585Y35567D01*
X2081430Y33900D01*
X2080810Y32441D01*
X2079880Y31608D01*
X2078950Y31400D01*
G01X2089180D02*
Y39733D01*
G01Y38067D02*
X2089955Y38900D01*
X2090730Y39525D01*
X2091815Y39733D01*
X2092590Y39525D01*
X2093520Y38900D01*
G01X2119250Y31400D02*
X2113050D01*
Y43900D01*
X2119250D01*
G01X2116770Y37858D02*
X2113050D01*
G01X2125450Y43900D02*
Y31400D01*
X2131650D01*
G01X2137850Y43900D02*
Y31400D01*
X2144050D01*
G01X2151490Y43900D02*
X2155210D01*
G01X2153350D02*
Y31400D01*
G01X2151490D02*
X2155210D01*
G01X2162650D02*
Y43900D01*
X2166370D01*
X2167610Y43275D01*
X2168540Y41817D01*
X2168850Y40150D01*
X2168540Y38483D01*
X2167765Y37233D01*
X2166370Y36608D01*
X2162650D01*
G01X2174895Y33066D02*
X2176135Y32025D01*
X2177530Y31400D01*
X2178770D01*
X2180010Y32025D01*
X2180940Y33066D01*
X2181405Y34525D01*
X2181095Y35983D01*
X2180320Y37233D01*
X2178925Y38067D01*
X2177065Y38483D01*
X2175980Y39317D01*
X2175515Y40775D01*
X2175825Y42233D01*
X2176600Y43275D01*
X2177685Y43900D01*
X2178770D01*
X2179855Y43483D01*
X2180785Y42442D01*
G01X2193650Y31400D02*
X2187450D01*
Y43900D01*
X2193650D01*
G01X2191170Y37858D02*
X2187450D01*
G01X2218140Y43900D02*
Y31400D01*
G01Y33275D02*
X2217520Y32233D01*
X2216590Y31608D01*
X2215505Y31400D01*
X2214265Y31817D01*
X2213335Y32858D01*
X2212715Y34108D01*
X2212560Y35567D01*
X2212715Y37025D01*
X2213335Y38275D01*
X2214265Y39317D01*
X2215505Y39733D01*
X2216590Y39525D01*
X2217365Y39108D01*
X2218140Y38275D01*
G01X2225580Y31400D02*
Y39733D01*
G01Y38067D02*
X2226355Y38900D01*
X2227130Y39525D01*
X2228215Y39733D01*
X2228990Y39525D01*
X2229920Y38900D01*
G01X2240150Y39733D02*
Y31400D01*
G01Y43066D02*
X2239840Y43275D01*
Y43692D01*
X2240150Y43900D01*
X2240460Y43692D01*
Y43275D01*
X2240150Y43066D01*
G01X2252550Y31400D02*
Y43900D01*
G01X2264950Y31400D02*
Y43900D01*
G01X2292540D02*
Y31400D01*
G01Y33275D02*
X2291920Y32233D01*
X2290990Y31608D01*
X2289905Y31400D01*
X2288665Y31817D01*
X2287735Y32858D01*
X2287115Y34108D01*
X2286960Y35567D01*
X2287115Y37025D01*
X2287735Y38275D01*
X2288665Y39317D01*
X2289905Y39733D01*
X2290990Y39525D01*
X2291765Y39108D01*
X2292540Y38275D01*
G01X2302150Y39733D02*
Y31400D01*
G01Y43066D02*
X2301840Y43275D01*
Y43692D01*
X2302150Y43900D01*
X2302460Y43692D01*
Y43275D01*
X2302150Y43066D01*
G01X2312380Y31400D02*
Y39733D01*
G01Y38067D02*
X2313155Y38900D01*
X2313930Y39525D01*
X2315015Y39733D01*
X2315790Y39525D01*
X2316720Y38900D01*
G01X2324625Y37025D02*
X2329585D01*
X2329120Y38483D01*
X2328345Y39317D01*
X2327260Y39733D01*
X2326175Y39525D01*
X2325245Y38900D01*
X2324625Y37442D01*
X2324315Y36191D01*
Y34942D01*
X2324625Y33692D01*
X2325400Y32441D01*
X2326330Y31608D01*
X2327415Y31400D01*
X2328500Y31817D01*
X2329585Y33066D01*
G01X2341830Y38692D02*
X2340745Y39525D01*
X2339815Y39733D01*
X2338575Y39317D01*
X2337645Y38483D01*
X2337025Y37025D01*
X2336870Y35567D01*
X2337025Y34108D01*
X2337645Y32858D01*
X2338575Y31817D01*
X2339815Y31400D01*
X2340900Y31817D01*
X2341830Y32650D01*
G01X2351750Y43900D02*
Y31400D01*
G01X2349580Y39733D02*
X2353920D01*
G01X2364150D02*
Y31400D01*
G01Y43066D02*
X2363840Y43275D01*
Y43692D01*
X2364150Y43900D01*
X2364460Y43692D01*
Y43275D01*
X2364150Y43066D01*
G01X2376550Y31400D02*
X2375620Y31608D01*
X2374690Y32441D01*
X2374070Y33900D01*
X2373760Y35567D01*
X2374070Y37233D01*
X2374690Y38692D01*
X2375620Y39525D01*
X2376550Y39733D01*
X2377480Y39525D01*
X2378410Y38692D01*
X2379030Y37233D01*
X2379185Y35567D01*
X2379030Y33900D01*
X2378410Y32441D01*
X2377480Y31608D01*
X2376550Y31400D01*
G01X2386315D02*
Y39733D01*
G01Y37650D02*
X2386935Y38692D01*
X2387865Y39525D01*
X2389105Y39733D01*
X2390190Y39525D01*
X2391120Y38692D01*
X2391585Y37233D01*
Y31400D01*
G01X1739500Y61400D02*
Y957500D01*
X2223100D01*
Y61400D01*
X1739500D01*
G01Y89500D02*
X2223100D01*
G01X1739500Y117600D02*
X2223100D01*
G01X1739500Y145700D02*
X2223100D01*
G01X1739500Y173800D02*
X2223100D01*
G01X1739500Y201900D02*
X2223100D01*
G01X1739500Y230000D02*
X2223100D01*
G01X1739500Y258100D02*
X2223100D01*
G01X1739500Y286200D02*
X2223100D01*
G01X1739500Y314300D02*
X2223100D01*
G01X1739500Y342400D02*
X2223100D01*
G01X1739500Y370500D02*
X2223100D01*
G01X1739500Y398600D02*
X2223100D01*
G01X1739500Y426700D02*
X2223100D01*
G01X1739500Y454800D02*
X2223100D01*
G01X1739500Y482900D02*
X2223100D01*
G01X1739500Y511000D02*
X2223100D01*
G01X1739500Y539100D02*
X2223100D01*
G01X1739500Y567200D02*
X2223100D01*
G01X1739500Y595300D02*
X2223100D01*
G01X1739500Y623400D02*
X2223100D01*
G01X1739500Y651500D02*
X2223100D01*
G01X1739500Y679600D02*
X2223100D01*
G01X1739500Y707700D02*
X2223100D01*
G01X1739500Y735800D02*
X2223100D01*
G01X1739500Y763900D02*
X2223100D01*
G01X1739500Y792000D02*
X2223100D01*
G01X1739500Y820100D02*
X2223100D01*
G01X1739500Y848200D02*
X2223100D01*
G01X1739500Y876300D02*
X2223100D01*
G01X1739500Y904400D02*
X2223100D01*
G01X1739500Y932500D02*
X2223100D01*
G01X1750505Y885650D02*
Y898150D01*
X1756395D01*
G01X1754225Y892108D02*
X1750505D01*
G01X1763990Y898150D02*
X1767710D01*
G01X1765850D02*
Y885650D01*
G01X1763990D02*
X1767710D01*
G01X1779180Y891900D02*
X1782280D01*
Y888150D01*
X1781350Y886900D01*
X1780265Y886067D01*
X1778715Y885650D01*
X1777165Y886067D01*
X1776080Y886900D01*
X1775150Y888150D01*
X1774530Y889608D01*
X1774220Y891275D01*
Y892733D01*
X1774530Y893983D01*
X1775150Y895442D01*
X1776080Y896692D01*
X1777010Y897525D01*
X1778250Y898150D01*
X1779335D01*
X1780575Y897733D01*
X1781505Y896900D01*
G01X1787240Y898150D02*
Y889192D01*
X1787860Y887316D01*
X1789100Y886067D01*
X1790650Y885650D01*
X1792200Y886067D01*
X1793440Y887316D01*
X1794060Y889192D01*
Y898150D01*
G01X1799950Y885650D02*
Y898150D01*
X1803825D01*
X1805065Y897525D01*
X1805840Y896692D01*
X1806150Y895025D01*
X1805840Y893358D01*
X1804910Y892317D01*
X1803825Y891692D01*
X1799950D01*
G01X1803825D02*
X1806150Y885650D01*
G01X1818550D02*
X1812350D01*
Y898150D01*
X1818550D01*
G01X1816070Y892108D02*
X1812350D01*
G01X1822890Y938750D02*
Y951250D01*
X1825990D01*
X1827230Y950625D01*
X1828160Y949792D01*
X1828935Y948542D01*
X1829555Y947083D01*
X1829710Y945000D01*
X1829555Y942917D01*
X1828935Y941458D01*
X1828160Y940208D01*
X1827230Y939375D01*
X1825990Y938750D01*
X1822890D01*
G01X1835600D02*
Y951250D01*
X1839475D01*
X1840715Y950625D01*
X1841490Y949792D01*
X1841800Y948125D01*
X1841490Y946458D01*
X1840560Y945417D01*
X1839475Y944792D01*
X1835600D01*
G01X1839475D02*
X1841800Y938750D01*
G01X1849240Y951250D02*
X1852960D01*
G01X1851100D02*
Y938750D01*
G01X1849240D02*
X1852960D01*
G01X1860400Y951250D02*
Y938750D01*
X1866600D01*
G01X1872800Y951250D02*
Y938750D01*
X1879000D01*
G01X1904110Y950208D02*
X1903180Y950833D01*
X1902095Y951250D01*
X1900855D01*
X1899460Y950625D01*
X1898375Y949583D01*
X1897600Y948333D01*
X1896980Y946250D01*
X1896825Y944375D01*
X1897135Y942500D01*
X1897600Y941250D01*
X1898530Y940000D01*
X1899615Y939167D01*
X1900700Y938750D01*
X1901785D01*
X1902870Y939167D01*
X1903800Y939791D01*
X1904575Y940625D01*
G01X1909845Y938750D02*
Y951250D01*
G01X1916355D02*
Y938750D01*
G01Y945000D02*
X1909845D01*
G01X1921625Y938750D02*
X1925500Y951250D01*
X1929375Y938750D01*
G01X1927980Y943125D02*
X1923020D01*
G01X1934800Y938750D02*
Y951250D01*
X1938675D01*
X1939915Y950625D01*
X1940690Y949792D01*
X1941000Y948125D01*
X1940690Y946458D01*
X1939760Y945417D01*
X1938675Y944792D01*
X1934800D01*
G01X1938675D02*
X1941000Y938750D01*
G01X1950300Y951250D02*
Y938750D01*
G01X1946735Y951250D02*
X1953865D01*
G01X1962700Y938333D02*
X1962390Y938542D01*
Y938958D01*
X1962700Y939167D01*
X1963010Y938958D01*
Y938542D01*
X1962700Y938333D01*
G01Y943958D02*
X1962390Y944167D01*
Y944583D01*
X1962700Y944792D01*
X1963010Y944583D01*
Y944167D01*
X1962700Y943958D01*
G01X1987500Y951250D02*
Y938750D01*
G01X1983935Y951250D02*
X1991065D01*
G01X1999900Y938750D02*
X1998660Y938958D01*
X1997575Y939791D01*
X1996645Y941042D01*
X1996025Y942500D01*
X1995715Y944167D01*
Y945833D01*
X1996025Y947500D01*
X1996645Y948958D01*
X1997575Y950208D01*
X1998660Y951042D01*
X1999900Y951250D01*
X2001140Y951042D01*
X2002225Y950208D01*
X2003155Y948958D01*
X2003775Y947500D01*
X2004085Y945833D01*
Y944167D01*
X2003775Y942500D01*
X2003155Y941042D01*
X2002225Y939791D01*
X2001140Y938958D01*
X1999900Y938750D01*
G01X2009200D02*
Y951250D01*
X2012920D01*
X2014160Y950625D01*
X2015090Y949167D01*
X2015400Y947500D01*
X2015090Y945833D01*
X2014315Y944583D01*
X2012920Y943958D01*
X2009200D01*
G01X2037100Y951250D02*
Y938750D01*
G01X2034930Y947083D02*
X2039270D01*
G01X2049500Y938750D02*
X2048570Y938958D01*
X2047640Y939791D01*
X2047020Y941250D01*
X2046710Y942917D01*
X2047020Y944583D01*
X2047640Y946042D01*
X2048570Y946875D01*
X2049500Y947083D01*
X2050430Y946875D01*
X2051360Y946042D01*
X2051980Y944583D01*
X2052135Y942917D01*
X2051980Y941250D01*
X2051360Y939791D01*
X2050430Y938958D01*
X2049500Y938750D01*
G01X2075540Y945417D02*
X2076160Y946042D01*
X2076625Y947083D01*
X2076935Y948542D01*
X2076625Y949792D01*
X2076005Y950625D01*
X2074920Y951250D01*
X2070735D01*
Y938750D01*
X2075850D01*
X2076935Y939583D01*
X2077555Y940833D01*
X2077865Y942292D01*
X2077555Y943750D01*
X2076625Y945000D01*
X2075540Y945417D01*
X2070735D01*
G01X2086700Y938750D02*
X2085460Y938958D01*
X2084375Y939791D01*
X2083445Y941042D01*
X2082825Y942500D01*
X2082515Y944167D01*
Y945833D01*
X2082825Y947500D01*
X2083445Y948958D01*
X2084375Y950208D01*
X2085460Y951042D01*
X2086700Y951250D01*
X2087940Y951042D01*
X2089025Y950208D01*
X2089955Y948958D01*
X2090575Y947500D01*
X2090885Y945833D01*
Y944167D01*
X2090575Y942500D01*
X2089955Y941042D01*
X2089025Y939791D01*
X2087940Y938958D01*
X2086700Y938750D01*
G01X2099100Y951250D02*
Y938750D01*
G01X2095535Y951250D02*
X2102665D01*
G01X2111500D02*
Y938750D01*
G01X2107935Y951250D02*
X2115065D01*
G01X2123900Y938750D02*
X2122660Y938958D01*
X2121575Y939791D01*
X2120645Y941042D01*
X2120025Y942500D01*
X2119715Y944167D01*
Y945833D01*
X2120025Y947500D01*
X2120645Y948958D01*
X2121575Y950208D01*
X2122660Y951042D01*
X2123900Y951250D01*
X2125140Y951042D01*
X2126225Y950208D01*
X2127155Y948958D01*
X2127775Y947500D01*
X2128085Y945833D01*
Y944167D01*
X2127775Y942500D01*
X2127155Y941042D01*
X2126225Y939791D01*
X2125140Y938958D01*
X2123900Y938750D01*
G01X2132270D02*
Y951250D01*
X2136300Y940833D01*
X2140330Y951250D01*
Y938750D01*
G01X1829400Y904400D02*
Y61400D01*
G01X1853425Y913750D02*
X1857300Y926250D01*
X1861175Y913750D01*
G01X1859780Y918125D02*
X1854820D01*
G01X1866600Y926250D02*
Y913750D01*
X1872800D01*
G01X1879000Y926250D02*
Y913750D01*
X1885200D01*
G01X1903490Y926250D02*
Y917292D01*
X1904110Y915416D01*
X1905350Y914167D01*
X1906900Y913750D01*
X1908450Y914167D01*
X1909690Y915416D01*
X1910310Y917292D01*
Y926250D01*
G01X1915735Y913750D02*
Y926250D01*
X1922865Y913750D01*
Y926250D01*
G01X1929840D02*
X1933560D01*
G01X1931700D02*
Y913750D01*
G01X1929840D02*
X1933560D01*
G01X1944100Y926250D02*
Y913750D01*
G01X1940535Y926250D02*
X1947665D01*
G01X1953245Y915416D02*
X1954485Y914375D01*
X1955880Y913750D01*
X1957120D01*
X1958360Y914375D01*
X1959290Y915416D01*
X1959755Y916875D01*
X1959445Y918333D01*
X1958670Y919583D01*
X1957275Y920417D01*
X1955415Y920833D01*
X1954330Y921667D01*
X1953865Y923125D01*
X1954175Y924583D01*
X1954950Y925625D01*
X1956035Y926250D01*
X1957120D01*
X1958205Y925833D01*
X1959135Y924792D01*
G01X1977425Y913750D02*
X1981300Y926250D01*
X1985175Y913750D01*
G01X1983780Y918125D02*
X1978820D01*
G01X1990600Y913750D02*
Y926250D01*
X1994475D01*
X1995715Y925625D01*
X1996490Y924792D01*
X1996800Y923125D01*
X1996490Y921458D01*
X1995560Y920417D01*
X1994475Y919792D01*
X1990600D01*
G01X1994475D02*
X1996800Y913750D01*
G01X2009200D02*
X2003000D01*
Y926250D01*
X2009200D01*
G01X2006720Y920208D02*
X2003000D01*
G01X2029040Y926250D02*
X2032760D01*
G01X2030900D02*
Y913750D01*
G01X2029040D02*
X2032760D01*
G01X2039735D02*
Y926250D01*
X2046865Y913750D01*
Y926250D01*
G01X2064070Y913750D02*
Y926250D01*
X2068100Y915833D01*
X2072130Y926250D01*
Y913750D01*
G01X2078640Y926250D02*
X2082360D01*
G01X2080500D02*
Y913750D01*
G01X2078640D02*
X2082360D01*
G01X2089800Y926250D02*
Y913750D01*
X2096000D01*
G01X2102045Y915416D02*
X2103285Y914375D01*
X2104680Y913750D01*
X2105920D01*
X2107160Y914375D01*
X2108090Y915416D01*
X2108555Y916875D01*
X2108245Y918333D01*
X2107470Y919583D01*
X2106075Y920417D01*
X2104215Y920833D01*
X2103130Y921667D01*
X2102665Y923125D01*
X2102975Y924583D01*
X2103750Y925625D01*
X2104835Y926250D01*
X2105920D01*
X2107005Y925833D01*
X2107935Y924792D01*
G01X1861950Y69200D02*
Y81700D01*
X1860090Y79200D01*
G01Y69200D02*
X1863810D01*
G01X1874350D02*
X1875435Y69408D01*
X1876675Y70033D01*
X1877450Y71075D01*
X1877760Y72533D01*
X1877450Y73991D01*
X1876520Y75242D01*
X1875125Y75867D01*
X1873575D01*
X1872645Y76283D01*
X1871870Y77325D01*
X1871560Y78783D01*
X1872025Y80242D01*
X1873110Y81283D01*
X1874350Y81700D01*
X1875590Y81283D01*
X1876675Y80242D01*
X1877140Y78783D01*
X1876830Y77325D01*
X1876055Y76283D01*
X1875125Y75867D01*
X1873575D01*
X1872180Y75242D01*
X1871250Y73991D01*
X1870940Y72533D01*
X1871250Y71075D01*
X1872025Y70033D01*
X1873265Y69408D01*
X1874350Y69200D01*
G01X1884115Y70658D02*
X1885200Y69617D01*
X1886440Y69200D01*
X1887680Y69617D01*
X1888765Y70866D01*
X1889540Y72742D01*
X1889850Y74617D01*
Y76908D01*
X1889540Y78783D01*
X1888765Y80450D01*
X1887835Y81283D01*
X1886750Y81700D01*
X1885510Y81283D01*
X1884580Y80450D01*
X1883960Y79200D01*
X1883650Y77533D01*
X1883960Y76075D01*
X1884735Y74617D01*
X1885665Y73783D01*
X1886750Y73575D01*
X1887990Y73991D01*
X1888920Y75033D01*
X1889850Y76908D01*
G01X1899150Y68783D02*
X1898840Y68992D01*
Y69408D01*
X1899150Y69617D01*
X1899460Y69408D01*
Y68992D01*
X1899150Y68783D01*
G01X1911550Y81700D02*
X1910310Y81283D01*
X1909380Y80242D01*
X1908760Y78992D01*
X1908295Y77325D01*
X1908140Y75450D01*
X1908295Y73575D01*
X1908760Y71908D01*
X1909380Y70658D01*
X1910310Y69617D01*
X1911550Y69200D01*
X1912790Y69617D01*
X1913720Y70658D01*
X1914340Y71908D01*
X1914805Y73575D01*
X1914960Y75450D01*
X1914805Y77325D01*
X1914340Y78992D01*
X1913720Y80242D01*
X1912790Y81283D01*
X1911550Y81700D01*
G01X1921625Y77533D02*
X1926275Y69200D01*
G01Y77533D02*
X1921625Y69200D01*
G01X1936350D02*
Y81700D01*
X1934490Y79200D01*
G01Y69200D02*
X1938210D01*
G01X1945805Y79617D02*
X1946735Y80866D01*
X1947820Y81492D01*
X1949060Y81700D01*
X1950610Y81283D01*
X1951695Y80242D01*
X1952005Y78992D01*
X1951850Y77741D01*
X1951230Y76700D01*
X1948130Y74617D01*
X1946735Y73158D01*
X1945805Y71075D01*
X1945495Y69200D01*
X1952005D01*
G01X1958205Y74408D02*
X1959290Y75867D01*
X1960220Y76700D01*
X1961460Y77117D01*
X1962545Y76700D01*
X1963320Y75867D01*
X1963940Y74617D01*
X1964095Y73158D01*
X1963940Y71908D01*
X1963320Y70658D01*
X1962390Y69617D01*
X1961305Y69200D01*
X1960065Y69617D01*
X1958980Y70866D01*
X1958360Y72742D01*
X1958205Y74825D01*
X1958515Y77533D01*
X1958980Y78992D01*
X1959755Y80450D01*
X1960840Y81492D01*
X1961925Y81700D01*
X1963010Y81283D01*
X1963785Y80242D01*
G01X1973550Y68783D02*
X1973240Y68992D01*
Y69408D01*
X1973550Y69617D01*
X1973860Y69408D01*
Y68992D01*
X1973550Y68783D01*
G01X1985950Y81700D02*
X1984710Y81283D01*
X1983780Y80242D01*
X1983160Y78992D01*
X1982695Y77325D01*
X1982540Y75450D01*
X1982695Y73575D01*
X1983160Y71908D01*
X1983780Y70658D01*
X1984710Y69617D01*
X1985950Y69200D01*
X1987190Y69617D01*
X1988120Y70658D01*
X1988740Y71908D01*
X1989205Y73575D01*
X1989360Y75450D01*
X1989205Y77325D01*
X1988740Y78992D01*
X1988120Y80242D01*
X1987190Y81283D01*
X1985950Y81700D01*
G01X1899150Y97300D02*
Y109800D01*
X1897290Y107300D01*
G01Y97300D02*
X1901010D01*
G01X1908140Y99800D02*
X1909070Y98341D01*
X1910310Y97508D01*
X1911705Y97300D01*
X1912945Y97508D01*
X1914185Y98550D01*
X1914960Y99800D01*
X1915115Y101050D01*
X1914805Y102508D01*
X1913720Y103550D01*
X1912635Y103967D01*
X1911240D01*
G01X1912635D02*
X1913565Y104592D01*
X1914340Y105633D01*
X1914650Y106883D01*
X1914340Y108133D01*
X1913565Y109175D01*
X1912170Y109800D01*
X1910775Y109592D01*
X1909380Y108758D01*
G01X1923950Y97300D02*
X1925035Y97508D01*
X1926275Y98133D01*
X1927050Y99175D01*
X1927360Y100633D01*
X1927050Y102091D01*
X1926120Y103342D01*
X1924725Y103967D01*
X1923175D01*
X1922245Y104383D01*
X1921470Y105425D01*
X1921160Y106883D01*
X1921625Y108342D01*
X1922710Y109383D01*
X1923950Y109800D01*
X1925190Y109383D01*
X1926275Y108342D01*
X1926740Y106883D01*
X1926430Y105425D01*
X1925655Y104383D01*
X1924725Y103967D01*
X1923175D01*
X1921780Y103342D01*
X1920850Y102091D01*
X1920540Y100633D01*
X1920850Y99175D01*
X1921625Y98133D01*
X1922865Y97508D01*
X1923950Y97300D01*
G01X1936350Y96883D02*
X1936040Y97092D01*
Y97508D01*
X1936350Y97717D01*
X1936660Y97508D01*
Y97092D01*
X1936350Y96883D01*
G01X1948750Y109800D02*
X1947510Y109383D01*
X1946580Y108342D01*
X1945960Y107092D01*
X1945495Y105425D01*
X1945340Y103550D01*
X1945495Y101675D01*
X1945960Y100008D01*
X1946580Y98758D01*
X1947510Y97717D01*
X1948750Y97300D01*
X1949990Y97717D01*
X1950920Y98758D01*
X1951540Y100008D01*
X1952005Y101675D01*
X1952160Y103550D01*
X1952005Y105425D01*
X1951540Y107092D01*
X1950920Y108342D01*
X1949990Y109383D01*
X1948750Y109800D01*
G01X1899150Y125400D02*
Y137900D01*
X1897290Y135400D01*
G01Y125400D02*
X1901010D01*
G01X1908605Y135817D02*
X1909535Y137066D01*
X1910620Y137692D01*
X1911860Y137900D01*
X1913410Y137483D01*
X1914495Y136442D01*
X1914805Y135192D01*
X1914650Y133941D01*
X1914030Y132900D01*
X1910930Y130817D01*
X1909535Y129358D01*
X1908605Y127275D01*
X1908295Y125400D01*
X1914805D01*
G01X1923950D02*
X1925035Y125608D01*
X1926275Y126233D01*
X1927050Y127275D01*
X1927360Y128733D01*
X1927050Y130191D01*
X1926120Y131442D01*
X1924725Y132067D01*
X1923175D01*
X1922245Y132483D01*
X1921470Y133525D01*
X1921160Y134983D01*
X1921625Y136442D01*
X1922710Y137483D01*
X1923950Y137900D01*
X1925190Y137483D01*
X1926275Y136442D01*
X1926740Y134983D01*
X1926430Y133525D01*
X1925655Y132483D01*
X1924725Y132067D01*
X1923175D01*
X1921780Y131442D01*
X1920850Y130191D01*
X1920540Y128733D01*
X1920850Y127275D01*
X1921625Y126233D01*
X1922865Y125608D01*
X1923950Y125400D01*
G01X1936350Y124983D02*
X1936040Y125192D01*
Y125608D01*
X1936350Y125817D01*
X1936660Y125608D01*
Y125192D01*
X1936350Y124983D01*
G01X1948750Y137900D02*
X1947510Y137483D01*
X1946580Y136442D01*
X1945960Y135192D01*
X1945495Y133525D01*
X1945340Y131650D01*
X1945495Y129775D01*
X1945960Y128108D01*
X1946580Y126858D01*
X1947510Y125817D01*
X1948750Y125400D01*
X1949990Y125817D01*
X1950920Y126858D01*
X1951540Y128108D01*
X1952005Y129775D01*
X1952160Y131650D01*
X1952005Y133525D01*
X1951540Y135192D01*
X1950920Y136442D01*
X1949990Y137483D01*
X1948750Y137900D01*
G01X1899150Y153500D02*
Y166000D01*
X1897290Y163500D01*
G01Y153500D02*
X1901010D01*
G01X1908605Y163917D02*
X1909535Y165166D01*
X1910620Y165792D01*
X1911860Y166000D01*
X1913410Y165583D01*
X1914495Y164542D01*
X1914805Y163292D01*
X1914650Y162041D01*
X1914030Y161000D01*
X1910930Y158917D01*
X1909535Y157458D01*
X1908605Y155375D01*
X1908295Y153500D01*
X1914805D01*
G01X1921005Y158708D02*
X1922090Y160167D01*
X1923020Y161000D01*
X1924260Y161417D01*
X1925345Y161000D01*
X1926120Y160167D01*
X1926740Y158917D01*
X1926895Y157458D01*
X1926740Y156208D01*
X1926120Y154958D01*
X1925190Y153917D01*
X1924105Y153500D01*
X1922865Y153917D01*
X1921780Y155166D01*
X1921160Y157042D01*
X1921005Y159125D01*
X1921315Y161833D01*
X1921780Y163292D01*
X1922555Y164750D01*
X1923640Y165792D01*
X1924725Y166000D01*
X1925810Y165583D01*
X1926585Y164542D01*
G01X1936350Y153083D02*
X1936040Y153292D01*
Y153708D01*
X1936350Y153917D01*
X1936660Y153708D01*
Y153292D01*
X1936350Y153083D01*
G01X1948750Y166000D02*
X1947510Y165583D01*
X1946580Y164542D01*
X1945960Y163292D01*
X1945495Y161625D01*
X1945340Y159750D01*
X1945495Y157875D01*
X1945960Y156208D01*
X1946580Y154958D01*
X1947510Y153917D01*
X1948750Y153500D01*
X1949990Y153917D01*
X1950920Y154958D01*
X1951540Y156208D01*
X1952005Y157875D01*
X1952160Y159750D01*
X1952005Y161625D01*
X1951540Y163292D01*
X1950920Y164542D01*
X1949990Y165583D01*
X1948750Y166000D01*
G01X1902715Y183058D02*
X1903800Y182017D01*
X1905040Y181600D01*
X1906280Y182017D01*
X1907365Y183266D01*
X1908140Y185142D01*
X1908450Y187017D01*
Y189308D01*
X1908140Y191183D01*
X1907365Y192850D01*
X1906435Y193683D01*
X1905350Y194100D01*
X1904110Y193683D01*
X1903180Y192850D01*
X1902560Y191600D01*
X1902250Y189933D01*
X1902560Y188475D01*
X1903335Y187017D01*
X1904265Y186183D01*
X1905350Y185975D01*
X1906590Y186391D01*
X1907520Y187433D01*
X1908450Y189308D01*
G01X1914340Y184100D02*
X1915270Y182641D01*
X1916510Y181808D01*
X1917905Y181600D01*
X1919145Y181808D01*
X1920385Y182850D01*
X1921160Y184100D01*
X1921315Y185350D01*
X1921005Y186808D01*
X1919920Y187850D01*
X1918835Y188267D01*
X1917440D01*
G01X1918835D02*
X1919765Y188892D01*
X1920540Y189933D01*
X1920850Y191183D01*
X1920540Y192433D01*
X1919765Y193475D01*
X1918370Y194100D01*
X1916975Y193892D01*
X1915580Y193058D01*
G01X1930150Y181183D02*
X1929840Y181392D01*
Y181808D01*
X1930150Y182017D01*
X1930460Y181808D01*
Y181392D01*
X1930150Y181183D01*
G01X1942550Y194100D02*
X1941310Y193683D01*
X1940380Y192642D01*
X1939760Y191392D01*
X1939295Y189725D01*
X1939140Y187850D01*
X1939295Y185975D01*
X1939760Y184308D01*
X1940380Y183058D01*
X1941310Y182017D01*
X1942550Y181600D01*
X1943790Y182017D01*
X1944720Y183058D01*
X1945340Y184308D01*
X1945805Y185975D01*
X1945960Y187850D01*
X1945805Y189725D01*
X1945340Y191392D01*
X1944720Y192642D01*
X1943790Y193683D01*
X1942550Y194100D01*
G01X1905350Y209700D02*
X1906435Y209908D01*
X1907675Y210533D01*
X1908450Y211575D01*
X1908760Y213033D01*
X1908450Y214491D01*
X1907520Y215742D01*
X1906125Y216367D01*
X1904575D01*
X1903645Y216783D01*
X1902870Y217825D01*
X1902560Y219283D01*
X1903025Y220742D01*
X1904110Y221783D01*
X1905350Y222200D01*
X1906590Y221783D01*
X1907675Y220742D01*
X1908140Y219283D01*
X1907830Y217825D01*
X1907055Y216783D01*
X1906125Y216367D01*
X1904575D01*
X1903180Y215742D01*
X1902250Y214491D01*
X1901940Y213033D01*
X1902250Y211575D01*
X1903025Y210533D01*
X1904265Y209908D01*
X1905350Y209700D01*
G01X1914805Y214908D02*
X1915890Y216367D01*
X1916820Y217200D01*
X1918060Y217617D01*
X1919145Y217200D01*
X1919920Y216367D01*
X1920540Y215117D01*
X1920695Y213658D01*
X1920540Y212408D01*
X1919920Y211158D01*
X1918990Y210117D01*
X1917905Y209700D01*
X1916665Y210117D01*
X1915580Y211366D01*
X1914960Y213242D01*
X1914805Y215325D01*
X1915115Y218033D01*
X1915580Y219492D01*
X1916355Y220950D01*
X1917440Y221992D01*
X1918525Y222200D01*
X1919610Y221783D01*
X1920385Y220742D01*
G01X1930150Y209283D02*
X1929840Y209492D01*
Y209908D01*
X1930150Y210117D01*
X1930460Y209908D01*
Y209492D01*
X1930150Y209283D01*
G01X1942550Y222200D02*
X1941310Y221783D01*
X1940380Y220742D01*
X1939760Y219492D01*
X1939295Y217825D01*
X1939140Y215950D01*
X1939295Y214075D01*
X1939760Y212408D01*
X1940380Y211158D01*
X1941310Y210117D01*
X1942550Y209700D01*
X1943790Y210117D01*
X1944720Y211158D01*
X1945340Y212408D01*
X1945805Y214075D01*
X1945960Y215950D01*
X1945805Y217825D01*
X1945340Y219492D01*
X1944720Y220742D01*
X1943790Y221783D01*
X1942550Y222200D01*
G01X1902405Y243008D02*
X1903490Y244467D01*
X1904420Y245300D01*
X1905660Y245717D01*
X1906745Y245300D01*
X1907520Y244467D01*
X1908140Y243217D01*
X1908295Y241758D01*
X1908140Y240508D01*
X1907520Y239258D01*
X1906590Y238217D01*
X1905505Y237800D01*
X1904265Y238217D01*
X1903180Y239466D01*
X1902560Y241342D01*
X1902405Y243425D01*
X1902715Y246133D01*
X1903180Y247592D01*
X1903955Y249050D01*
X1905040Y250092D01*
X1906125Y250300D01*
X1907210Y249883D01*
X1907985Y248842D01*
G01X1914805Y248217D02*
X1915735Y249466D01*
X1916820Y250092D01*
X1918060Y250300D01*
X1919610Y249883D01*
X1920695Y248842D01*
X1921005Y247592D01*
X1920850Y246341D01*
X1920230Y245300D01*
X1917130Y243217D01*
X1915735Y241758D01*
X1914805Y239675D01*
X1914495Y237800D01*
X1921005D01*
G01X1930150Y237383D02*
X1929840Y237592D01*
Y238008D01*
X1930150Y238217D01*
X1930460Y238008D01*
Y237592D01*
X1930150Y237383D01*
G01X1942550Y250300D02*
X1941310Y249883D01*
X1940380Y248842D01*
X1939760Y247592D01*
X1939295Y245925D01*
X1939140Y244050D01*
X1939295Y242175D01*
X1939760Y240508D01*
X1940380Y239258D01*
X1941310Y238217D01*
X1942550Y237800D01*
X1943790Y238217D01*
X1944720Y239258D01*
X1945340Y240508D01*
X1945805Y242175D01*
X1945960Y244050D01*
X1945805Y245925D01*
X1945340Y247592D01*
X1944720Y248842D01*
X1943790Y249883D01*
X1942550Y250300D01*
G01X1902405Y271108D02*
X1903490Y272567D01*
X1904420Y273400D01*
X1905660Y273817D01*
X1906745Y273400D01*
X1907520Y272567D01*
X1908140Y271317D01*
X1908295Y269858D01*
X1908140Y268608D01*
X1907520Y267358D01*
X1906590Y266317D01*
X1905505Y265900D01*
X1904265Y266317D01*
X1903180Y267566D01*
X1902560Y269442D01*
X1902405Y271525D01*
X1902715Y274233D01*
X1903180Y275692D01*
X1903955Y277150D01*
X1905040Y278192D01*
X1906125Y278400D01*
X1907210Y277983D01*
X1907985Y276942D01*
G01X1917750Y265900D02*
Y278400D01*
X1915890Y275900D01*
G01Y265900D02*
X1919610D01*
G01X1930150Y265483D02*
X1929840Y265692D01*
Y266108D01*
X1930150Y266317D01*
X1930460Y266108D01*
Y265692D01*
X1930150Y265483D01*
G01X1942550Y278400D02*
X1941310Y277983D01*
X1940380Y276942D01*
X1939760Y275692D01*
X1939295Y274025D01*
X1939140Y272150D01*
X1939295Y270275D01*
X1939760Y268608D01*
X1940380Y267358D01*
X1941310Y266317D01*
X1942550Y265900D01*
X1943790Y266317D01*
X1944720Y267358D01*
X1945340Y268608D01*
X1945805Y270275D01*
X1945960Y272150D01*
X1945805Y274025D01*
X1945340Y275692D01*
X1944720Y276942D01*
X1943790Y277983D01*
X1942550Y278400D01*
G01X1907210Y294000D02*
Y306500D01*
X1901475Y297542D01*
X1909225D01*
G01X1917750Y294000D02*
X1918835Y294208D01*
X1920075Y294833D01*
X1920850Y295875D01*
X1921160Y297333D01*
X1920850Y298791D01*
X1919920Y300042D01*
X1918525Y300667D01*
X1916975D01*
X1916045Y301083D01*
X1915270Y302125D01*
X1914960Y303583D01*
X1915425Y305042D01*
X1916510Y306083D01*
X1917750Y306500D01*
X1918990Y306083D01*
X1920075Y305042D01*
X1920540Y303583D01*
X1920230Y302125D01*
X1919455Y301083D01*
X1918525Y300667D01*
X1916975D01*
X1915580Y300042D01*
X1914650Y298791D01*
X1914340Y297333D01*
X1914650Y295875D01*
X1915425Y294833D01*
X1916665Y294208D01*
X1917750Y294000D01*
G01X1930150Y293583D02*
X1929840Y293792D01*
Y294208D01*
X1930150Y294417D01*
X1930460Y294208D01*
Y293792D01*
X1930150Y293583D01*
G01X1942550Y306500D02*
X1941310Y306083D01*
X1940380Y305042D01*
X1939760Y303792D01*
X1939295Y302125D01*
X1939140Y300250D01*
X1939295Y298375D01*
X1939760Y296708D01*
X1940380Y295458D01*
X1941310Y294417D01*
X1942550Y294000D01*
X1943790Y294417D01*
X1944720Y295458D01*
X1945340Y296708D01*
X1945805Y298375D01*
X1945960Y300250D01*
X1945805Y302125D01*
X1945340Y303792D01*
X1944720Y305042D01*
X1943790Y306083D01*
X1942550Y306500D01*
G01X1907210Y322100D02*
Y334600D01*
X1901475Y325642D01*
X1909225D01*
G01X1917750Y334600D02*
X1916510Y334183D01*
X1915580Y333142D01*
X1914960Y331892D01*
X1914495Y330225D01*
X1914340Y328350D01*
X1914495Y326475D01*
X1914960Y324808D01*
X1915580Y323558D01*
X1916510Y322517D01*
X1917750Y322100D01*
X1918990Y322517D01*
X1919920Y323558D01*
X1920540Y324808D01*
X1921005Y326475D01*
X1921160Y328350D01*
X1921005Y330225D01*
X1920540Y331892D01*
X1919920Y333142D01*
X1918990Y334183D01*
X1917750Y334600D01*
G01X1930150Y321683D02*
X1929840Y321892D01*
Y322308D01*
X1930150Y322517D01*
X1930460Y322308D01*
Y321892D01*
X1930150Y321683D01*
G01X1942550Y334600D02*
X1941310Y334183D01*
X1940380Y333142D01*
X1939760Y331892D01*
X1939295Y330225D01*
X1939140Y328350D01*
X1939295Y326475D01*
X1939760Y324808D01*
X1940380Y323558D01*
X1941310Y322517D01*
X1942550Y322100D01*
X1943790Y322517D01*
X1944720Y323558D01*
X1945340Y324808D01*
X1945805Y326475D01*
X1945960Y328350D01*
X1945805Y330225D01*
X1945340Y331892D01*
X1944720Y333142D01*
X1943790Y334183D01*
X1942550Y334600D01*
G01X1901940Y352700D02*
X1902870Y351241D01*
X1904110Y350408D01*
X1905505Y350200D01*
X1906745Y350408D01*
X1907985Y351450D01*
X1908760Y352700D01*
X1908915Y353950D01*
X1908605Y355408D01*
X1907520Y356450D01*
X1906435Y356867D01*
X1905040D01*
G01X1906435D02*
X1907365Y357492D01*
X1908140Y358533D01*
X1908450Y359783D01*
X1908140Y361033D01*
X1907365Y362075D01*
X1905970Y362700D01*
X1904575Y362492D01*
X1903180Y361658D01*
G01X1917750Y350200D02*
X1918835Y350408D01*
X1920075Y351033D01*
X1920850Y352075D01*
X1921160Y353533D01*
X1920850Y354991D01*
X1919920Y356242D01*
X1918525Y356867D01*
X1916975D01*
X1916045Y357283D01*
X1915270Y358325D01*
X1914960Y359783D01*
X1915425Y361242D01*
X1916510Y362283D01*
X1917750Y362700D01*
X1918990Y362283D01*
X1920075Y361242D01*
X1920540Y359783D01*
X1920230Y358325D01*
X1919455Y357283D01*
X1918525Y356867D01*
X1916975D01*
X1915580Y356242D01*
X1914650Y354991D01*
X1914340Y353533D01*
X1914650Y352075D01*
X1915425Y351033D01*
X1916665Y350408D01*
X1917750Y350200D01*
G01X1930150Y349783D02*
X1929840Y349992D01*
Y350408D01*
X1930150Y350617D01*
X1930460Y350408D01*
Y349992D01*
X1930150Y349783D01*
G01X1942550Y362700D02*
X1941310Y362283D01*
X1940380Y361242D01*
X1939760Y359992D01*
X1939295Y358325D01*
X1939140Y356450D01*
X1939295Y354575D01*
X1939760Y352908D01*
X1940380Y351658D01*
X1941310Y350617D01*
X1942550Y350200D01*
X1943790Y350617D01*
X1944720Y351658D01*
X1945340Y352908D01*
X1945805Y354575D01*
X1945960Y356450D01*
X1945805Y358325D01*
X1945340Y359992D01*
X1944720Y361242D01*
X1943790Y362283D01*
X1942550Y362700D01*
G01X1901940Y380800D02*
X1902870Y379341D01*
X1904110Y378508D01*
X1905505Y378300D01*
X1906745Y378508D01*
X1907985Y379550D01*
X1908760Y380800D01*
X1908915Y382050D01*
X1908605Y383508D01*
X1907520Y384550D01*
X1906435Y384967D01*
X1905040D01*
G01X1906435D02*
X1907365Y385592D01*
X1908140Y386633D01*
X1908450Y387883D01*
X1908140Y389133D01*
X1907365Y390175D01*
X1905970Y390800D01*
X1904575Y390592D01*
X1903180Y389758D01*
G01X1919610Y378300D02*
Y390800D01*
X1913875Y381842D01*
X1921625D01*
G01X1930150Y377883D02*
X1929840Y378092D01*
Y378508D01*
X1930150Y378717D01*
X1930460Y378508D01*
Y378092D01*
X1930150Y377883D01*
G01X1942550Y390800D02*
X1941310Y390383D01*
X1940380Y389342D01*
X1939760Y388092D01*
X1939295Y386425D01*
X1939140Y384550D01*
X1939295Y382675D01*
X1939760Y381008D01*
X1940380Y379758D01*
X1941310Y378717D01*
X1942550Y378300D01*
X1943790Y378717D01*
X1944720Y379758D01*
X1945340Y381008D01*
X1945805Y382675D01*
X1945960Y384550D01*
X1945805Y386425D01*
X1945340Y388092D01*
X1944720Y389342D01*
X1943790Y390383D01*
X1942550Y390800D01*
G01X1901940Y408900D02*
X1902870Y407441D01*
X1904110Y406608D01*
X1905505Y406400D01*
X1906745Y406608D01*
X1907985Y407650D01*
X1908760Y408900D01*
X1908915Y410150D01*
X1908605Y411608D01*
X1907520Y412650D01*
X1906435Y413067D01*
X1905040D01*
G01X1906435D02*
X1907365Y413692D01*
X1908140Y414733D01*
X1908450Y415983D01*
X1908140Y417233D01*
X1907365Y418275D01*
X1905970Y418900D01*
X1904575Y418692D01*
X1903180Y417858D01*
G01X1914805Y416817D02*
X1915735Y418066D01*
X1916820Y418692D01*
X1918060Y418900D01*
X1919610Y418483D01*
X1920695Y417442D01*
X1921005Y416192D01*
X1920850Y414941D01*
X1920230Y413900D01*
X1917130Y411817D01*
X1915735Y410358D01*
X1914805Y408275D01*
X1914495Y406400D01*
X1921005D01*
G01X1930150Y405983D02*
X1929840Y406192D01*
Y406608D01*
X1930150Y406817D01*
X1930460Y406608D01*
Y406192D01*
X1930150Y405983D01*
G01X1942550Y418900D02*
X1941310Y418483D01*
X1940380Y417442D01*
X1939760Y416192D01*
X1939295Y414525D01*
X1939140Y412650D01*
X1939295Y410775D01*
X1939760Y409108D01*
X1940380Y407858D01*
X1941310Y406817D01*
X1942550Y406400D01*
X1943790Y406817D01*
X1944720Y407858D01*
X1945340Y409108D01*
X1945805Y410775D01*
X1945960Y412650D01*
X1945805Y414525D01*
X1945340Y416192D01*
X1944720Y417442D01*
X1943790Y418483D01*
X1942550Y418900D01*
G01X1902715Y435958D02*
X1903800Y434917D01*
X1905040Y434500D01*
X1906280Y434917D01*
X1907365Y436166D01*
X1908140Y438042D01*
X1908450Y439917D01*
Y442208D01*
X1908140Y444083D01*
X1907365Y445750D01*
X1906435Y446583D01*
X1905350Y447000D01*
X1904110Y446583D01*
X1903180Y445750D01*
X1902560Y444500D01*
X1902250Y442833D01*
X1902560Y441375D01*
X1903335Y439917D01*
X1904265Y439083D01*
X1905350Y438875D01*
X1906590Y439291D01*
X1907520Y440333D01*
X1908450Y442208D01*
G01X1915115Y435958D02*
X1916200Y434917D01*
X1917440Y434500D01*
X1918680Y434917D01*
X1919765Y436166D01*
X1920540Y438042D01*
X1920850Y439917D01*
Y442208D01*
X1920540Y444083D01*
X1919765Y445750D01*
X1918835Y446583D01*
X1917750Y447000D01*
X1916510Y446583D01*
X1915580Y445750D01*
X1914960Y444500D01*
X1914650Y442833D01*
X1914960Y441375D01*
X1915735Y439917D01*
X1916665Y439083D01*
X1917750Y438875D01*
X1918990Y439291D01*
X1919920Y440333D01*
X1920850Y442208D01*
G01X1930150Y434083D02*
X1929840Y434292D01*
Y434708D01*
X1930150Y434917D01*
X1930460Y434708D01*
Y434292D01*
X1930150Y434083D01*
G01X1942550Y447000D02*
X1941310Y446583D01*
X1940380Y445542D01*
X1939760Y444292D01*
X1939295Y442625D01*
X1939140Y440750D01*
X1939295Y438875D01*
X1939760Y437208D01*
X1940380Y435958D01*
X1941310Y434917D01*
X1942550Y434500D01*
X1943790Y434917D01*
X1944720Y435958D01*
X1945340Y437208D01*
X1945805Y438875D01*
X1945960Y440750D01*
X1945805Y442625D01*
X1945340Y444292D01*
X1944720Y445542D01*
X1943790Y446583D01*
X1942550Y447000D01*
G01X1902715Y464058D02*
X1903800Y463017D01*
X1905040Y462600D01*
X1906280Y463017D01*
X1907365Y464266D01*
X1908140Y466142D01*
X1908450Y468017D01*
Y470308D01*
X1908140Y472183D01*
X1907365Y473850D01*
X1906435Y474683D01*
X1905350Y475100D01*
X1904110Y474683D01*
X1903180Y473850D01*
X1902560Y472600D01*
X1902250Y470933D01*
X1902560Y469475D01*
X1903335Y468017D01*
X1904265Y467183D01*
X1905350Y466975D01*
X1906590Y467391D01*
X1907520Y468433D01*
X1908450Y470308D01*
G01X1917750Y462600D02*
Y475100D01*
X1915890Y472600D01*
G01Y462600D02*
X1919610D01*
G01X1930150Y462183D02*
X1929840Y462392D01*
Y462808D01*
X1930150Y463017D01*
X1930460Y462808D01*
Y462392D01*
X1930150Y462183D01*
G01X1942550Y475100D02*
X1941310Y474683D01*
X1940380Y473642D01*
X1939760Y472392D01*
X1939295Y470725D01*
X1939140Y468850D01*
X1939295Y466975D01*
X1939760Y465308D01*
X1940380Y464058D01*
X1941310Y463017D01*
X1942550Y462600D01*
X1943790Y463017D01*
X1944720Y464058D01*
X1945340Y465308D01*
X1945805Y466975D01*
X1945960Y468850D01*
X1945805Y470725D01*
X1945340Y472392D01*
X1944720Y473642D01*
X1943790Y474683D01*
X1942550Y475100D01*
G01X1902405Y495908D02*
X1903490Y497367D01*
X1904420Y498200D01*
X1905660Y498617D01*
X1906745Y498200D01*
X1907520Y497367D01*
X1908140Y496117D01*
X1908295Y494658D01*
X1908140Y493408D01*
X1907520Y492158D01*
X1906590Y491117D01*
X1905505Y490700D01*
X1904265Y491117D01*
X1903180Y492366D01*
X1902560Y494242D01*
X1902405Y496325D01*
X1902715Y499033D01*
X1903180Y500492D01*
X1903955Y501950D01*
X1905040Y502992D01*
X1906125Y503200D01*
X1907210Y502783D01*
X1907985Y501742D01*
G01X1914805Y501117D02*
X1915735Y502366D01*
X1916820Y502992D01*
X1918060Y503200D01*
X1919610Y502783D01*
X1920695Y501742D01*
X1921005Y500492D01*
X1920850Y499241D01*
X1920230Y498200D01*
X1917130Y496117D01*
X1915735Y494658D01*
X1914805Y492575D01*
X1914495Y490700D01*
X1921005D01*
G01X1930150Y490283D02*
X1929840Y490492D01*
Y490908D01*
X1930150Y491117D01*
X1930460Y490908D01*
Y490492D01*
X1930150Y490283D01*
G01X1942550Y503200D02*
X1941310Y502783D01*
X1940380Y501742D01*
X1939760Y500492D01*
X1939295Y498825D01*
X1939140Y496950D01*
X1939295Y495075D01*
X1939760Y493408D01*
X1940380Y492158D01*
X1941310Y491117D01*
X1942550Y490700D01*
X1943790Y491117D01*
X1944720Y492158D01*
X1945340Y493408D01*
X1945805Y495075D01*
X1945960Y496950D01*
X1945805Y498825D01*
X1945340Y500492D01*
X1944720Y501742D01*
X1943790Y502783D01*
X1942550Y503200D01*
G01X1901940Y520675D02*
X1902870Y519633D01*
X1903955Y519008D01*
X1905350Y518800D01*
X1906745Y519217D01*
X1907830Y520050D01*
X1908605Y521508D01*
X1908760Y523175D01*
X1908450Y524842D01*
X1907675Y525883D01*
X1906590Y526717D01*
X1905505Y526925D01*
X1904420Y526717D01*
X1903025Y525883D01*
X1903490Y531300D01*
X1907675D01*
G01X1917750D02*
X1916510Y530883D01*
X1915580Y529842D01*
X1914960Y528592D01*
X1914495Y526925D01*
X1914340Y525050D01*
X1914495Y523175D01*
X1914960Y521508D01*
X1915580Y520258D01*
X1916510Y519217D01*
X1917750Y518800D01*
X1918990Y519217D01*
X1919920Y520258D01*
X1920540Y521508D01*
X1921005Y523175D01*
X1921160Y525050D01*
X1921005Y526925D01*
X1920540Y528592D01*
X1919920Y529842D01*
X1918990Y530883D01*
X1917750Y531300D01*
G01X1930150Y518383D02*
X1929840Y518592D01*
Y519008D01*
X1930150Y519217D01*
X1930460Y519008D01*
Y518592D01*
X1930150Y518383D01*
G01X1942550Y531300D02*
X1941310Y530883D01*
X1940380Y529842D01*
X1939760Y528592D01*
X1939295Y526925D01*
X1939140Y525050D01*
X1939295Y523175D01*
X1939760Y521508D01*
X1940380Y520258D01*
X1941310Y519217D01*
X1942550Y518800D01*
X1943790Y519217D01*
X1944720Y520258D01*
X1945340Y521508D01*
X1945805Y523175D01*
X1945960Y525050D01*
X1945805Y526925D01*
X1945340Y528592D01*
X1944720Y529842D01*
X1943790Y530883D01*
X1942550Y531300D01*
G01X1907210Y546900D02*
Y559400D01*
X1901475Y550442D01*
X1909225D01*
G01X1914340Y548775D02*
X1915270Y547733D01*
X1916355Y547108D01*
X1917750Y546900D01*
X1919145Y547317D01*
X1920230Y548150D01*
X1921005Y549608D01*
X1921160Y551275D01*
X1920850Y552942D01*
X1920075Y553983D01*
X1918990Y554817D01*
X1917905Y555025D01*
X1916820Y554817D01*
X1915425Y553983D01*
X1915890Y559400D01*
X1920075D01*
G01X1930150Y546483D02*
X1929840Y546692D01*
Y547108D01*
X1930150Y547317D01*
X1930460Y547108D01*
Y546692D01*
X1930150Y546483D01*
G01X1942550Y559400D02*
X1941310Y558983D01*
X1940380Y557942D01*
X1939760Y556692D01*
X1939295Y555025D01*
X1939140Y553150D01*
X1939295Y551275D01*
X1939760Y549608D01*
X1940380Y548358D01*
X1941310Y547317D01*
X1942550Y546900D01*
X1943790Y547317D01*
X1944720Y548358D01*
X1945340Y549608D01*
X1945805Y551275D01*
X1945960Y553150D01*
X1945805Y555025D01*
X1945340Y556692D01*
X1944720Y557942D01*
X1943790Y558983D01*
X1942550Y559400D01*
G01X1907210Y575000D02*
Y587500D01*
X1901475Y578542D01*
X1909225D01*
G01X1914805Y585417D02*
X1915735Y586666D01*
X1916820Y587292D01*
X1918060Y587500D01*
X1919610Y587083D01*
X1920695Y586042D01*
X1921005Y584792D01*
X1920850Y583541D01*
X1920230Y582500D01*
X1917130Y580417D01*
X1915735Y578958D01*
X1914805Y576875D01*
X1914495Y575000D01*
X1921005D01*
G01X1930150Y574583D02*
X1929840Y574792D01*
Y575208D01*
X1930150Y575417D01*
X1930460Y575208D01*
Y574792D01*
X1930150Y574583D01*
G01X1942550Y587500D02*
X1941310Y587083D01*
X1940380Y586042D01*
X1939760Y584792D01*
X1939295Y583125D01*
X1939140Y581250D01*
X1939295Y579375D01*
X1939760Y577708D01*
X1940380Y576458D01*
X1941310Y575417D01*
X1942550Y575000D01*
X1943790Y575417D01*
X1944720Y576458D01*
X1945340Y577708D01*
X1945805Y579375D01*
X1945960Y581250D01*
X1945805Y583125D01*
X1945340Y584792D01*
X1944720Y586042D01*
X1943790Y587083D01*
X1942550Y587500D01*
G01X1907210Y603100D02*
Y615600D01*
X1901475Y606642D01*
X1909225D01*
G01X1917750Y615600D02*
X1916510Y615183D01*
X1915580Y614142D01*
X1914960Y612892D01*
X1914495Y611225D01*
X1914340Y609350D01*
X1914495Y607475D01*
X1914960Y605808D01*
X1915580Y604558D01*
X1916510Y603517D01*
X1917750Y603100D01*
X1918990Y603517D01*
X1919920Y604558D01*
X1920540Y605808D01*
X1921005Y607475D01*
X1921160Y609350D01*
X1921005Y611225D01*
X1920540Y612892D01*
X1919920Y614142D01*
X1918990Y615183D01*
X1917750Y615600D01*
G01X1930150Y602683D02*
X1929840Y602892D01*
Y603308D01*
X1930150Y603517D01*
X1930460Y603308D01*
Y602892D01*
X1930150Y602683D01*
G01X1942550Y615600D02*
X1941310Y615183D01*
X1940380Y614142D01*
X1939760Y612892D01*
X1939295Y611225D01*
X1939140Y609350D01*
X1939295Y607475D01*
X1939760Y605808D01*
X1940380Y604558D01*
X1941310Y603517D01*
X1942550Y603100D01*
X1943790Y603517D01*
X1944720Y604558D01*
X1945340Y605808D01*
X1945805Y607475D01*
X1945960Y609350D01*
X1945805Y611225D01*
X1945340Y612892D01*
X1944720Y614142D01*
X1943790Y615183D01*
X1942550Y615600D01*
G01X1901940Y633700D02*
X1902870Y632241D01*
X1904110Y631408D01*
X1905505Y631200D01*
X1906745Y631408D01*
X1907985Y632450D01*
X1908760Y633700D01*
X1908915Y634950D01*
X1908605Y636408D01*
X1907520Y637450D01*
X1906435Y637867D01*
X1905040D01*
G01X1906435D02*
X1907365Y638492D01*
X1908140Y639533D01*
X1908450Y640783D01*
X1908140Y642033D01*
X1907365Y643075D01*
X1905970Y643700D01*
X1904575Y643492D01*
X1903180Y642658D01*
G01X1917750Y631200D02*
X1918835Y631408D01*
X1920075Y632033D01*
X1920850Y633075D01*
X1921160Y634533D01*
X1920850Y635991D01*
X1919920Y637242D01*
X1918525Y637867D01*
X1916975D01*
X1916045Y638283D01*
X1915270Y639325D01*
X1914960Y640783D01*
X1915425Y642242D01*
X1916510Y643283D01*
X1917750Y643700D01*
X1918990Y643283D01*
X1920075Y642242D01*
X1920540Y640783D01*
X1920230Y639325D01*
X1919455Y638283D01*
X1918525Y637867D01*
X1916975D01*
X1915580Y637242D01*
X1914650Y635991D01*
X1914340Y634533D01*
X1914650Y633075D01*
X1915425Y632033D01*
X1916665Y631408D01*
X1917750Y631200D01*
G01X1930150Y630783D02*
X1929840Y630992D01*
Y631408D01*
X1930150Y631617D01*
X1930460Y631408D01*
Y630992D01*
X1930150Y630783D01*
G01X1942550Y643700D02*
X1941310Y643283D01*
X1940380Y642242D01*
X1939760Y640992D01*
X1939295Y639325D01*
X1939140Y637450D01*
X1939295Y635575D01*
X1939760Y633908D01*
X1940380Y632658D01*
X1941310Y631617D01*
X1942550Y631200D01*
X1943790Y631617D01*
X1944720Y632658D01*
X1945340Y633908D01*
X1945805Y635575D01*
X1945960Y637450D01*
X1945805Y639325D01*
X1945340Y640992D01*
X1944720Y642242D01*
X1943790Y643283D01*
X1942550Y643700D01*
G01X1901940Y661800D02*
X1902870Y660341D01*
X1904110Y659508D01*
X1905505Y659300D01*
X1906745Y659508D01*
X1907985Y660550D01*
X1908760Y661800D01*
X1908915Y663050D01*
X1908605Y664508D01*
X1907520Y665550D01*
X1906435Y665967D01*
X1905040D01*
G01X1906435D02*
X1907365Y666592D01*
X1908140Y667633D01*
X1908450Y668883D01*
X1908140Y670133D01*
X1907365Y671175D01*
X1905970Y671800D01*
X1904575Y671592D01*
X1903180Y670758D01*
G01X1914805Y664508D02*
X1915890Y665967D01*
X1916820Y666800D01*
X1918060Y667217D01*
X1919145Y666800D01*
X1919920Y665967D01*
X1920540Y664717D01*
X1920695Y663258D01*
X1920540Y662008D01*
X1919920Y660758D01*
X1918990Y659717D01*
X1917905Y659300D01*
X1916665Y659717D01*
X1915580Y660966D01*
X1914960Y662842D01*
X1914805Y664925D01*
X1915115Y667633D01*
X1915580Y669092D01*
X1916355Y670550D01*
X1917440Y671592D01*
X1918525Y671800D01*
X1919610Y671383D01*
X1920385Y670342D01*
G01X1930150Y658883D02*
X1929840Y659092D01*
Y659508D01*
X1930150Y659717D01*
X1930460Y659508D01*
Y659092D01*
X1930150Y658883D01*
G01X1942550Y671800D02*
X1941310Y671383D01*
X1940380Y670342D01*
X1939760Y669092D01*
X1939295Y667425D01*
X1939140Y665550D01*
X1939295Y663675D01*
X1939760Y662008D01*
X1940380Y660758D01*
X1941310Y659717D01*
X1942550Y659300D01*
X1943790Y659717D01*
X1944720Y660758D01*
X1945340Y662008D01*
X1945805Y663675D01*
X1945960Y665550D01*
X1945805Y667425D01*
X1945340Y669092D01*
X1944720Y670342D01*
X1943790Y671383D01*
X1942550Y671800D01*
G01X1901940Y689900D02*
X1902870Y688441D01*
X1904110Y687608D01*
X1905505Y687400D01*
X1906745Y687608D01*
X1907985Y688650D01*
X1908760Y689900D01*
X1908915Y691150D01*
X1908605Y692608D01*
X1907520Y693650D01*
X1906435Y694067D01*
X1905040D01*
G01X1906435D02*
X1907365Y694692D01*
X1908140Y695733D01*
X1908450Y696983D01*
X1908140Y698233D01*
X1907365Y699275D01*
X1905970Y699900D01*
X1904575Y699692D01*
X1903180Y698858D01*
G01X1914340Y689275D02*
X1915270Y688233D01*
X1916355Y687608D01*
X1917750Y687400D01*
X1919145Y687817D01*
X1920230Y688650D01*
X1921005Y690108D01*
X1921160Y691775D01*
X1920850Y693442D01*
X1920075Y694483D01*
X1918990Y695317D01*
X1917905Y695525D01*
X1916820Y695317D01*
X1915425Y694483D01*
X1915890Y699900D01*
X1920075D01*
G01X1930150Y686983D02*
X1929840Y687192D01*
Y687608D01*
X1930150Y687817D01*
X1930460Y687608D01*
Y687192D01*
X1930150Y686983D01*
G01X1942550Y699900D02*
X1941310Y699483D01*
X1940380Y698442D01*
X1939760Y697192D01*
X1939295Y695525D01*
X1939140Y693650D01*
X1939295Y691775D01*
X1939760Y690108D01*
X1940380Y688858D01*
X1941310Y687817D01*
X1942550Y687400D01*
X1943790Y687817D01*
X1944720Y688858D01*
X1945340Y690108D01*
X1945805Y691775D01*
X1945960Y693650D01*
X1945805Y695525D01*
X1945340Y697192D01*
X1944720Y698442D01*
X1943790Y699483D01*
X1942550Y699900D01*
G01X1901940Y718000D02*
X1902870Y716541D01*
X1904110Y715708D01*
X1905505Y715500D01*
X1906745Y715708D01*
X1907985Y716750D01*
X1908760Y718000D01*
X1908915Y719250D01*
X1908605Y720708D01*
X1907520Y721750D01*
X1906435Y722167D01*
X1905040D01*
G01X1906435D02*
X1907365Y722792D01*
X1908140Y723833D01*
X1908450Y725083D01*
X1908140Y726333D01*
X1907365Y727375D01*
X1905970Y728000D01*
X1904575Y727792D01*
X1903180Y726958D01*
G01X1914805Y725917D02*
X1915735Y727166D01*
X1916820Y727792D01*
X1918060Y728000D01*
X1919610Y727583D01*
X1920695Y726542D01*
X1921005Y725292D01*
X1920850Y724041D01*
X1920230Y723000D01*
X1917130Y720917D01*
X1915735Y719458D01*
X1914805Y717375D01*
X1914495Y715500D01*
X1921005D01*
G01X1930150Y715083D02*
X1929840Y715292D01*
Y715708D01*
X1930150Y715917D01*
X1930460Y715708D01*
Y715292D01*
X1930150Y715083D01*
G01X1942550Y728000D02*
X1941310Y727583D01*
X1940380Y726542D01*
X1939760Y725292D01*
X1939295Y723625D01*
X1939140Y721750D01*
X1939295Y719875D01*
X1939760Y718208D01*
X1940380Y716958D01*
X1941310Y715917D01*
X1942550Y715500D01*
X1943790Y715917D01*
X1944720Y716958D01*
X1945340Y718208D01*
X1945805Y719875D01*
X1945960Y721750D01*
X1945805Y723625D01*
X1945340Y725292D01*
X1944720Y726542D01*
X1943790Y727583D01*
X1942550Y728000D01*
G01X1901940Y746100D02*
X1902870Y744641D01*
X1904110Y743808D01*
X1905505Y743600D01*
X1906745Y743808D01*
X1907985Y744850D01*
X1908760Y746100D01*
X1908915Y747350D01*
X1908605Y748808D01*
X1907520Y749850D01*
X1906435Y750267D01*
X1905040D01*
G01X1906435D02*
X1907365Y750892D01*
X1908140Y751933D01*
X1908450Y753183D01*
X1908140Y754433D01*
X1907365Y755475D01*
X1905970Y756100D01*
X1904575Y755892D01*
X1903180Y755058D01*
G01X1917750Y743600D02*
Y756100D01*
X1915890Y753600D01*
G01Y743600D02*
X1919610D01*
G01X1930150Y743183D02*
X1929840Y743392D01*
Y743808D01*
X1930150Y744017D01*
X1930460Y743808D01*
Y743392D01*
X1930150Y743183D01*
G01X1942550Y756100D02*
X1941310Y755683D01*
X1940380Y754642D01*
X1939760Y753392D01*
X1939295Y751725D01*
X1939140Y749850D01*
X1939295Y747975D01*
X1939760Y746308D01*
X1940380Y745058D01*
X1941310Y744017D01*
X1942550Y743600D01*
X1943790Y744017D01*
X1944720Y745058D01*
X1945340Y746308D01*
X1945805Y747975D01*
X1945960Y749850D01*
X1945805Y751725D01*
X1945340Y753392D01*
X1944720Y754642D01*
X1943790Y755683D01*
X1942550Y756100D01*
G01X1902405Y782117D02*
X1903335Y783366D01*
X1904420Y783992D01*
X1905660Y784200D01*
X1907210Y783783D01*
X1908295Y782742D01*
X1908605Y781492D01*
X1908450Y780241D01*
X1907830Y779200D01*
X1904730Y777117D01*
X1903335Y775658D01*
X1902405Y773575D01*
X1902095Y771700D01*
X1908605D01*
G01X1915115Y773158D02*
X1916200Y772117D01*
X1917440Y771700D01*
X1918680Y772117D01*
X1919765Y773366D01*
X1920540Y775242D01*
X1920850Y777117D01*
Y779408D01*
X1920540Y781283D01*
X1919765Y782950D01*
X1918835Y783783D01*
X1917750Y784200D01*
X1916510Y783783D01*
X1915580Y782950D01*
X1914960Y781700D01*
X1914650Y780033D01*
X1914960Y778575D01*
X1915735Y777117D01*
X1916665Y776283D01*
X1917750Y776075D01*
X1918990Y776491D01*
X1919920Y777533D01*
X1920850Y779408D01*
G01X1930150Y771283D02*
X1929840Y771492D01*
Y771908D01*
X1930150Y772117D01*
X1930460Y771908D01*
Y771492D01*
X1930150Y771283D01*
G01X1942550Y784200D02*
X1941310Y783783D01*
X1940380Y782742D01*
X1939760Y781492D01*
X1939295Y779825D01*
X1939140Y777950D01*
X1939295Y776075D01*
X1939760Y774408D01*
X1940380Y773158D01*
X1941310Y772117D01*
X1942550Y771700D01*
X1943790Y772117D01*
X1944720Y773158D01*
X1945340Y774408D01*
X1945805Y776075D01*
X1945960Y777950D01*
X1945805Y779825D01*
X1945340Y781492D01*
X1944720Y782742D01*
X1943790Y783783D01*
X1942550Y784200D01*
G01X1905350Y799800D02*
Y812300D01*
X1903490Y809800D01*
G01Y799800D02*
X1907210D01*
G01X1914805Y805008D02*
X1915890Y806467D01*
X1916820Y807300D01*
X1918060Y807717D01*
X1919145Y807300D01*
X1919920Y806467D01*
X1920540Y805217D01*
X1920695Y803758D01*
X1920540Y802508D01*
X1919920Y801258D01*
X1918990Y800217D01*
X1917905Y799800D01*
X1916665Y800217D01*
X1915580Y801466D01*
X1914960Y803342D01*
X1914805Y805425D01*
X1915115Y808133D01*
X1915580Y809592D01*
X1916355Y811050D01*
X1917440Y812092D01*
X1918525Y812300D01*
X1919610Y811883D01*
X1920385Y810842D01*
G01X1930150Y799383D02*
X1929840Y799592D01*
Y800008D01*
X1930150Y800217D01*
X1930460Y800008D01*
Y799592D01*
X1930150Y799383D01*
G01X1942550Y812300D02*
X1941310Y811883D01*
X1940380Y810842D01*
X1939760Y809592D01*
X1939295Y807925D01*
X1939140Y806050D01*
X1939295Y804175D01*
X1939760Y802508D01*
X1940380Y801258D01*
X1941310Y800217D01*
X1942550Y799800D01*
X1943790Y800217D01*
X1944720Y801258D01*
X1945340Y802508D01*
X1945805Y804175D01*
X1945960Y806050D01*
X1945805Y807925D01*
X1945340Y809592D01*
X1944720Y810842D01*
X1943790Y811883D01*
X1942550Y812300D01*
G01X1905350Y827900D02*
Y840400D01*
X1903490Y837900D01*
G01Y827900D02*
X1907210D01*
G01X1914805Y838317D02*
X1915735Y839566D01*
X1916820Y840192D01*
X1918060Y840400D01*
X1919610Y839983D01*
X1920695Y838942D01*
X1921005Y837692D01*
X1920850Y836441D01*
X1920230Y835400D01*
X1917130Y833317D01*
X1915735Y831858D01*
X1914805Y829775D01*
X1914495Y827900D01*
X1921005D01*
G01X1930150Y827483D02*
X1929840Y827692D01*
Y828108D01*
X1930150Y828317D01*
X1930460Y828108D01*
Y827692D01*
X1930150Y827483D01*
G01X1942550Y840400D02*
X1941310Y839983D01*
X1940380Y838942D01*
X1939760Y837692D01*
X1939295Y836025D01*
X1939140Y834150D01*
X1939295Y832275D01*
X1939760Y830608D01*
X1940380Y829358D01*
X1941310Y828317D01*
X1942550Y827900D01*
X1943790Y828317D01*
X1944720Y829358D01*
X1945340Y830608D01*
X1945805Y832275D01*
X1945960Y834150D01*
X1945805Y836025D01*
X1945340Y837692D01*
X1944720Y838942D01*
X1943790Y839983D01*
X1942550Y840400D01*
G01X1905350Y856000D02*
Y868500D01*
X1903490Y866000D01*
G01Y856000D02*
X1907210D01*
G01X1917750Y868500D02*
X1916510Y868083D01*
X1915580Y867042D01*
X1914960Y865792D01*
X1914495Y864125D01*
X1914340Y862250D01*
X1914495Y860375D01*
X1914960Y858708D01*
X1915580Y857458D01*
X1916510Y856417D01*
X1917750Y856000D01*
X1918990Y856417D01*
X1919920Y857458D01*
X1920540Y858708D01*
X1921005Y860375D01*
X1921160Y862250D01*
X1921005Y864125D01*
X1920540Y865792D01*
X1919920Y867042D01*
X1918990Y868083D01*
X1917750Y868500D01*
G01X1930150Y855583D02*
X1929840Y855792D01*
Y856208D01*
X1930150Y856417D01*
X1930460Y856208D01*
Y855792D01*
X1930150Y855583D01*
G01X1942550Y868500D02*
X1941310Y868083D01*
X1940380Y867042D01*
X1939760Y865792D01*
X1939295Y864125D01*
X1939140Y862250D01*
X1939295Y860375D01*
X1939760Y858708D01*
X1940380Y857458D01*
X1941310Y856417D01*
X1942550Y856000D01*
X1943790Y856417D01*
X1944720Y857458D01*
X1945340Y858708D01*
X1945805Y860375D01*
X1945960Y862250D01*
X1945805Y864125D01*
X1945340Y865792D01*
X1944720Y867042D01*
X1943790Y868083D01*
X1942550Y868500D01*
G01X1902095Y887316D02*
X1903335Y886275D01*
X1904730Y885650D01*
X1905970D01*
X1907210Y886275D01*
X1908140Y887316D01*
X1908605Y888775D01*
X1908295Y890233D01*
X1907520Y891483D01*
X1906125Y892317D01*
X1904265Y892733D01*
X1903180Y893567D01*
X1902715Y895025D01*
X1903025Y896483D01*
X1903800Y897525D01*
X1904885Y898150D01*
X1905970D01*
X1907055Y897733D01*
X1907985Y896692D01*
G01X1915890Y898150D02*
X1919610D01*
G01X1917750D02*
Y885650D01*
G01X1915890D02*
X1919610D01*
G01X1927205Y898150D02*
X1933095D01*
X1927205Y885650D01*
X1933095D01*
G01X1945650D02*
X1939450D01*
Y898150D01*
X1945650D01*
G01X1943170Y892108D02*
X1939450D01*
G01X2018500Y904400D02*
Y61400D01*
G01X2022685Y69200D02*
Y81700D01*
X2029815Y69200D01*
Y81700D01*
G01X2038650Y69200D02*
X2037410Y69408D01*
X2036325Y70241D01*
X2035395Y71492D01*
X2034775Y72950D01*
X2034465Y74617D01*
Y76283D01*
X2034775Y77950D01*
X2035395Y79408D01*
X2036325Y80658D01*
X2037410Y81492D01*
X2038650Y81700D01*
X2039890Y81492D01*
X2040975Y80658D01*
X2041905Y79408D01*
X2042525Y77950D01*
X2042835Y76283D01*
Y74617D01*
X2042525Y72950D01*
X2041905Y71492D01*
X2040975Y70241D01*
X2039890Y69408D01*
X2038650Y69200D01*
G01X2047485D02*
Y81700D01*
X2054615Y69200D01*
Y81700D01*
G01X2061435Y73367D02*
X2065465D01*
G01X2072750Y69200D02*
Y81700D01*
X2076470D01*
X2077710Y81075D01*
X2078640Y79617D01*
X2078950Y77950D01*
X2078640Y76283D01*
X2077865Y75033D01*
X2076470Y74408D01*
X2072750D01*
G01X2085150Y81700D02*
Y69200D01*
X2091350D01*
G01X2096775D02*
X2100650Y81700D01*
X2104525Y69200D01*
G01X2103130Y73575D02*
X2098170D01*
G01X2113050Y81700D02*
Y69200D01*
G01X2109485Y81700D02*
X2116615D01*
G01X2128550Y69200D02*
X2122350D01*
Y81700D01*
X2128550D01*
G01X2126070Y75658D02*
X2122350D01*
G01X2134440Y69200D02*
Y81700D01*
X2137540D01*
X2138780Y81075D01*
X2139710Y80242D01*
X2140485Y78992D01*
X2141105Y77533D01*
X2141260Y75450D01*
X2141105Y73367D01*
X2140485Y71908D01*
X2139710Y70658D01*
X2138780Y69825D01*
X2137540Y69200D01*
X2134440D01*
G01X2022685Y97300D02*
Y109800D01*
X2029815Y97300D01*
Y109800D01*
G01X2038650Y97300D02*
X2037410Y97508D01*
X2036325Y98341D01*
X2035395Y99592D01*
X2034775Y101050D01*
X2034465Y102717D01*
Y104383D01*
X2034775Y106050D01*
X2035395Y107508D01*
X2036325Y108758D01*
X2037410Y109592D01*
X2038650Y109800D01*
X2039890Y109592D01*
X2040975Y108758D01*
X2041905Y107508D01*
X2042525Y106050D01*
X2042835Y104383D01*
Y102717D01*
X2042525Y101050D01*
X2041905Y99592D01*
X2040975Y98341D01*
X2039890Y97508D01*
X2038650Y97300D01*
G01X2047485D02*
Y109800D01*
X2054615Y97300D01*
Y109800D01*
G01X2061435Y101467D02*
X2065465D01*
G01X2072750Y97300D02*
Y109800D01*
X2076470D01*
X2077710Y109175D01*
X2078640Y107717D01*
X2078950Y106050D01*
X2078640Y104383D01*
X2077865Y103133D01*
X2076470Y102508D01*
X2072750D01*
G01X2085150Y109800D02*
Y97300D01*
X2091350D01*
G01X2096775D02*
X2100650Y109800D01*
X2104525Y97300D01*
G01X2103130Y101675D02*
X2098170D01*
G01X2113050Y109800D02*
Y97300D01*
G01X2109485Y109800D02*
X2116615D01*
G01X2128550Y97300D02*
X2122350D01*
Y109800D01*
X2128550D01*
G01X2126070Y103758D02*
X2122350D01*
G01X2134440Y97300D02*
Y109800D01*
X2137540D01*
X2138780Y109175D01*
X2139710Y108342D01*
X2140485Y107092D01*
X2141105Y105633D01*
X2141260Y103550D01*
X2141105Y101467D01*
X2140485Y100008D01*
X2139710Y98758D01*
X2138780Y97925D01*
X2137540Y97300D01*
X2134440D01*
G01X2022685Y125400D02*
Y137900D01*
X2029815Y125400D01*
Y137900D01*
G01X2038650Y125400D02*
X2037410Y125608D01*
X2036325Y126441D01*
X2035395Y127692D01*
X2034775Y129150D01*
X2034465Y130817D01*
Y132483D01*
X2034775Y134150D01*
X2035395Y135608D01*
X2036325Y136858D01*
X2037410Y137692D01*
X2038650Y137900D01*
X2039890Y137692D01*
X2040975Y136858D01*
X2041905Y135608D01*
X2042525Y134150D01*
X2042835Y132483D01*
Y130817D01*
X2042525Y129150D01*
X2041905Y127692D01*
X2040975Y126441D01*
X2039890Y125608D01*
X2038650Y125400D01*
G01X2047485D02*
Y137900D01*
X2054615Y125400D01*
Y137900D01*
G01X2061435Y129567D02*
X2065465D01*
G01X2072750Y125400D02*
Y137900D01*
X2076470D01*
X2077710Y137275D01*
X2078640Y135817D01*
X2078950Y134150D01*
X2078640Y132483D01*
X2077865Y131233D01*
X2076470Y130608D01*
X2072750D01*
G01X2085150Y137900D02*
Y125400D01*
X2091350D01*
G01X2096775D02*
X2100650Y137900D01*
X2104525Y125400D01*
G01X2103130Y129775D02*
X2098170D01*
G01X2113050Y137900D02*
Y125400D01*
G01X2109485Y137900D02*
X2116615D01*
G01X2128550Y125400D02*
X2122350D01*
Y137900D01*
X2128550D01*
G01X2126070Y131858D02*
X2122350D01*
G01X2134440Y125400D02*
Y137900D01*
X2137540D01*
X2138780Y137275D01*
X2139710Y136442D01*
X2140485Y135192D01*
X2141105Y133733D01*
X2141260Y131650D01*
X2141105Y129567D01*
X2140485Y128108D01*
X2139710Y126858D01*
X2138780Y126025D01*
X2137540Y125400D01*
X2134440D01*
G01X2022685Y153500D02*
Y166000D01*
X2029815Y153500D01*
Y166000D01*
G01X2038650Y153500D02*
X2037410Y153708D01*
X2036325Y154541D01*
X2035395Y155792D01*
X2034775Y157250D01*
X2034465Y158917D01*
Y160583D01*
X2034775Y162250D01*
X2035395Y163708D01*
X2036325Y164958D01*
X2037410Y165792D01*
X2038650Y166000D01*
X2039890Y165792D01*
X2040975Y164958D01*
X2041905Y163708D01*
X2042525Y162250D01*
X2042835Y160583D01*
Y158917D01*
X2042525Y157250D01*
X2041905Y155792D01*
X2040975Y154541D01*
X2039890Y153708D01*
X2038650Y153500D01*
G01X2047485D02*
Y166000D01*
X2054615Y153500D01*
Y166000D01*
G01X2061435Y157667D02*
X2065465D01*
G01X2072750Y153500D02*
Y166000D01*
X2076470D01*
X2077710Y165375D01*
X2078640Y163917D01*
X2078950Y162250D01*
X2078640Y160583D01*
X2077865Y159333D01*
X2076470Y158708D01*
X2072750D01*
G01X2085150Y166000D02*
Y153500D01*
X2091350D01*
G01X2096775D02*
X2100650Y166000D01*
X2104525Y153500D01*
G01X2103130Y157875D02*
X2098170D01*
G01X2113050Y166000D02*
Y153500D01*
G01X2109485Y166000D02*
X2116615D01*
G01X2128550Y153500D02*
X2122350D01*
Y166000D01*
X2128550D01*
G01X2126070Y159958D02*
X2122350D01*
G01X2134440Y153500D02*
Y166000D01*
X2137540D01*
X2138780Y165375D01*
X2139710Y164542D01*
X2140485Y163292D01*
X2141105Y161833D01*
X2141260Y159750D01*
X2141105Y157667D01*
X2140485Y156208D01*
X2139710Y154958D01*
X2138780Y154125D01*
X2137540Y153500D01*
X2134440D01*
G01X2022685Y181600D02*
Y194100D01*
X2029815Y181600D01*
Y194100D01*
G01X2038650Y181600D02*
X2037410Y181808D01*
X2036325Y182641D01*
X2035395Y183892D01*
X2034775Y185350D01*
X2034465Y187017D01*
Y188683D01*
X2034775Y190350D01*
X2035395Y191808D01*
X2036325Y193058D01*
X2037410Y193892D01*
X2038650Y194100D01*
X2039890Y193892D01*
X2040975Y193058D01*
X2041905Y191808D01*
X2042525Y190350D01*
X2042835Y188683D01*
Y187017D01*
X2042525Y185350D01*
X2041905Y183892D01*
X2040975Y182641D01*
X2039890Y181808D01*
X2038650Y181600D01*
G01X2047485D02*
Y194100D01*
X2054615Y181600D01*
Y194100D01*
G01X2061435Y185767D02*
X2065465D01*
G01X2072750Y181600D02*
Y194100D01*
X2076470D01*
X2077710Y193475D01*
X2078640Y192017D01*
X2078950Y190350D01*
X2078640Y188683D01*
X2077865Y187433D01*
X2076470Y186808D01*
X2072750D01*
G01X2085150Y194100D02*
Y181600D01*
X2091350D01*
G01X2096775D02*
X2100650Y194100D01*
X2104525Y181600D01*
G01X2103130Y185975D02*
X2098170D01*
G01X2113050Y194100D02*
Y181600D01*
G01X2109485Y194100D02*
X2116615D01*
G01X2128550Y181600D02*
X2122350D01*
Y194100D01*
X2128550D01*
G01X2126070Y188058D02*
X2122350D01*
G01X2134440Y181600D02*
Y194100D01*
X2137540D01*
X2138780Y193475D01*
X2139710Y192642D01*
X2140485Y191392D01*
X2141105Y189933D01*
X2141260Y187850D01*
X2141105Y185767D01*
X2140485Y184308D01*
X2139710Y183058D01*
X2138780Y182225D01*
X2137540Y181600D01*
X2134440D01*
G01X2022685Y209700D02*
Y222200D01*
X2029815Y209700D01*
Y222200D01*
G01X2038650Y209700D02*
X2037410Y209908D01*
X2036325Y210741D01*
X2035395Y211992D01*
X2034775Y213450D01*
X2034465Y215117D01*
Y216783D01*
X2034775Y218450D01*
X2035395Y219908D01*
X2036325Y221158D01*
X2037410Y221992D01*
X2038650Y222200D01*
X2039890Y221992D01*
X2040975Y221158D01*
X2041905Y219908D01*
X2042525Y218450D01*
X2042835Y216783D01*
Y215117D01*
X2042525Y213450D01*
X2041905Y211992D01*
X2040975Y210741D01*
X2039890Y209908D01*
X2038650Y209700D01*
G01X2047485D02*
Y222200D01*
X2054615Y209700D01*
Y222200D01*
G01X2061435Y213867D02*
X2065465D01*
G01X2072750Y209700D02*
Y222200D01*
X2076470D01*
X2077710Y221575D01*
X2078640Y220117D01*
X2078950Y218450D01*
X2078640Y216783D01*
X2077865Y215533D01*
X2076470Y214908D01*
X2072750D01*
G01X2085150Y222200D02*
Y209700D01*
X2091350D01*
G01X2096775D02*
X2100650Y222200D01*
X2104525Y209700D01*
G01X2103130Y214075D02*
X2098170D01*
G01X2113050Y222200D02*
Y209700D01*
G01X2109485Y222200D02*
X2116615D01*
G01X2128550Y209700D02*
X2122350D01*
Y222200D01*
X2128550D01*
G01X2126070Y216158D02*
X2122350D01*
G01X2134440Y209700D02*
Y222200D01*
X2137540D01*
X2138780Y221575D01*
X2139710Y220742D01*
X2140485Y219492D01*
X2141105Y218033D01*
X2141260Y215950D01*
X2141105Y213867D01*
X2140485Y212408D01*
X2139710Y211158D01*
X2138780Y210325D01*
X2137540Y209700D01*
X2134440D01*
G01X2022685Y237800D02*
Y250300D01*
X2029815Y237800D01*
Y250300D01*
G01X2038650Y237800D02*
X2037410Y238008D01*
X2036325Y238841D01*
X2035395Y240092D01*
X2034775Y241550D01*
X2034465Y243217D01*
Y244883D01*
X2034775Y246550D01*
X2035395Y248008D01*
X2036325Y249258D01*
X2037410Y250092D01*
X2038650Y250300D01*
X2039890Y250092D01*
X2040975Y249258D01*
X2041905Y248008D01*
X2042525Y246550D01*
X2042835Y244883D01*
Y243217D01*
X2042525Y241550D01*
X2041905Y240092D01*
X2040975Y238841D01*
X2039890Y238008D01*
X2038650Y237800D01*
G01X2047485D02*
Y250300D01*
X2054615Y237800D01*
Y250300D01*
G01X2061435Y241967D02*
X2065465D01*
G01X2072750Y237800D02*
Y250300D01*
X2076470D01*
X2077710Y249675D01*
X2078640Y248217D01*
X2078950Y246550D01*
X2078640Y244883D01*
X2077865Y243633D01*
X2076470Y243008D01*
X2072750D01*
G01X2085150Y250300D02*
Y237800D01*
X2091350D01*
G01X2096775D02*
X2100650Y250300D01*
X2104525Y237800D01*
G01X2103130Y242175D02*
X2098170D01*
G01X2113050Y250300D02*
Y237800D01*
G01X2109485Y250300D02*
X2116615D01*
G01X2128550Y237800D02*
X2122350D01*
Y250300D01*
X2128550D01*
G01X2126070Y244258D02*
X2122350D01*
G01X2134440Y237800D02*
Y250300D01*
X2137540D01*
X2138780Y249675D01*
X2139710Y248842D01*
X2140485Y247592D01*
X2141105Y246133D01*
X2141260Y244050D01*
X2141105Y241967D01*
X2140485Y240508D01*
X2139710Y239258D01*
X2138780Y238425D01*
X2137540Y237800D01*
X2134440D01*
G01X2022685Y265900D02*
Y278400D01*
X2029815Y265900D01*
Y278400D01*
G01X2038650Y265900D02*
X2037410Y266108D01*
X2036325Y266941D01*
X2035395Y268192D01*
X2034775Y269650D01*
X2034465Y271317D01*
Y272983D01*
X2034775Y274650D01*
X2035395Y276108D01*
X2036325Y277358D01*
X2037410Y278192D01*
X2038650Y278400D01*
X2039890Y278192D01*
X2040975Y277358D01*
X2041905Y276108D01*
X2042525Y274650D01*
X2042835Y272983D01*
Y271317D01*
X2042525Y269650D01*
X2041905Y268192D01*
X2040975Y266941D01*
X2039890Y266108D01*
X2038650Y265900D01*
G01X2047485D02*
Y278400D01*
X2054615Y265900D01*
Y278400D01*
G01X2061435Y270067D02*
X2065465D01*
G01X2072750Y265900D02*
Y278400D01*
X2076470D01*
X2077710Y277775D01*
X2078640Y276317D01*
X2078950Y274650D01*
X2078640Y272983D01*
X2077865Y271733D01*
X2076470Y271108D01*
X2072750D01*
G01X2085150Y278400D02*
Y265900D01*
X2091350D01*
G01X2096775D02*
X2100650Y278400D01*
X2104525Y265900D01*
G01X2103130Y270275D02*
X2098170D01*
G01X2113050Y278400D02*
Y265900D01*
G01X2109485Y278400D02*
X2116615D01*
G01X2128550Y265900D02*
X2122350D01*
Y278400D01*
X2128550D01*
G01X2126070Y272358D02*
X2122350D01*
G01X2134440Y265900D02*
Y278400D01*
X2137540D01*
X2138780Y277775D01*
X2139710Y276942D01*
X2140485Y275692D01*
X2141105Y274233D01*
X2141260Y272150D01*
X2141105Y270067D01*
X2140485Y268608D01*
X2139710Y267358D01*
X2138780Y266525D01*
X2137540Y265900D01*
X2134440D01*
G01X2022685Y294000D02*
Y306500D01*
X2029815Y294000D01*
Y306500D01*
G01X2038650Y294000D02*
X2037410Y294208D01*
X2036325Y295041D01*
X2035395Y296292D01*
X2034775Y297750D01*
X2034465Y299417D01*
Y301083D01*
X2034775Y302750D01*
X2035395Y304208D01*
X2036325Y305458D01*
X2037410Y306292D01*
X2038650Y306500D01*
X2039890Y306292D01*
X2040975Y305458D01*
X2041905Y304208D01*
X2042525Y302750D01*
X2042835Y301083D01*
Y299417D01*
X2042525Y297750D01*
X2041905Y296292D01*
X2040975Y295041D01*
X2039890Y294208D01*
X2038650Y294000D01*
G01X2047485D02*
Y306500D01*
X2054615Y294000D01*
Y306500D01*
G01X2061435Y298167D02*
X2065465D01*
G01X2072750Y294000D02*
Y306500D01*
X2076470D01*
X2077710Y305875D01*
X2078640Y304417D01*
X2078950Y302750D01*
X2078640Y301083D01*
X2077865Y299833D01*
X2076470Y299208D01*
X2072750D01*
G01X2085150Y306500D02*
Y294000D01*
X2091350D01*
G01X2096775D02*
X2100650Y306500D01*
X2104525Y294000D01*
G01X2103130Y298375D02*
X2098170D01*
G01X2113050Y306500D02*
Y294000D01*
G01X2109485Y306500D02*
X2116615D01*
G01X2128550Y294000D02*
X2122350D01*
Y306500D01*
X2128550D01*
G01X2126070Y300458D02*
X2122350D01*
G01X2134440Y294000D02*
Y306500D01*
X2137540D01*
X2138780Y305875D01*
X2139710Y305042D01*
X2140485Y303792D01*
X2141105Y302333D01*
X2141260Y300250D01*
X2141105Y298167D01*
X2140485Y296708D01*
X2139710Y295458D01*
X2138780Y294625D01*
X2137540Y294000D01*
X2134440D01*
G01X2022685Y322100D02*
Y334600D01*
X2029815Y322100D01*
Y334600D01*
G01X2038650Y322100D02*
X2037410Y322308D01*
X2036325Y323141D01*
X2035395Y324392D01*
X2034775Y325850D01*
X2034465Y327517D01*
Y329183D01*
X2034775Y330850D01*
X2035395Y332308D01*
X2036325Y333558D01*
X2037410Y334392D01*
X2038650Y334600D01*
X2039890Y334392D01*
X2040975Y333558D01*
X2041905Y332308D01*
X2042525Y330850D01*
X2042835Y329183D01*
Y327517D01*
X2042525Y325850D01*
X2041905Y324392D01*
X2040975Y323141D01*
X2039890Y322308D01*
X2038650Y322100D01*
G01X2047485D02*
Y334600D01*
X2054615Y322100D01*
Y334600D01*
G01X2061435Y326267D02*
X2065465D01*
G01X2072750Y322100D02*
Y334600D01*
X2076470D01*
X2077710Y333975D01*
X2078640Y332517D01*
X2078950Y330850D01*
X2078640Y329183D01*
X2077865Y327933D01*
X2076470Y327308D01*
X2072750D01*
G01X2085150Y334600D02*
Y322100D01*
X2091350D01*
G01X2096775D02*
X2100650Y334600D01*
X2104525Y322100D01*
G01X2103130Y326475D02*
X2098170D01*
G01X2113050Y334600D02*
Y322100D01*
G01X2109485Y334600D02*
X2116615D01*
G01X2128550Y322100D02*
X2122350D01*
Y334600D01*
X2128550D01*
G01X2126070Y328558D02*
X2122350D01*
G01X2134440Y322100D02*
Y334600D01*
X2137540D01*
X2138780Y333975D01*
X2139710Y333142D01*
X2140485Y331892D01*
X2141105Y330433D01*
X2141260Y328350D01*
X2141105Y326267D01*
X2140485Y324808D01*
X2139710Y323558D01*
X2138780Y322725D01*
X2137540Y322100D01*
X2134440D01*
G01X2022685Y350200D02*
Y362700D01*
X2029815Y350200D01*
Y362700D01*
G01X2038650Y350200D02*
X2037410Y350408D01*
X2036325Y351241D01*
X2035395Y352492D01*
X2034775Y353950D01*
X2034465Y355617D01*
Y357283D01*
X2034775Y358950D01*
X2035395Y360408D01*
X2036325Y361658D01*
X2037410Y362492D01*
X2038650Y362700D01*
X2039890Y362492D01*
X2040975Y361658D01*
X2041905Y360408D01*
X2042525Y358950D01*
X2042835Y357283D01*
Y355617D01*
X2042525Y353950D01*
X2041905Y352492D01*
X2040975Y351241D01*
X2039890Y350408D01*
X2038650Y350200D01*
G01X2047485D02*
Y362700D01*
X2054615Y350200D01*
Y362700D01*
G01X2061435Y354367D02*
X2065465D01*
G01X2072750Y350200D02*
Y362700D01*
X2076470D01*
X2077710Y362075D01*
X2078640Y360617D01*
X2078950Y358950D01*
X2078640Y357283D01*
X2077865Y356033D01*
X2076470Y355408D01*
X2072750D01*
G01X2085150Y362700D02*
Y350200D01*
X2091350D01*
G01X2096775D02*
X2100650Y362700D01*
X2104525Y350200D01*
G01X2103130Y354575D02*
X2098170D01*
G01X2113050Y362700D02*
Y350200D01*
G01X2109485Y362700D02*
X2116615D01*
G01X2128550Y350200D02*
X2122350D01*
Y362700D01*
X2128550D01*
G01X2126070Y356658D02*
X2122350D01*
G01X2134440Y350200D02*
Y362700D01*
X2137540D01*
X2138780Y362075D01*
X2139710Y361242D01*
X2140485Y359992D01*
X2141105Y358533D01*
X2141260Y356450D01*
X2141105Y354367D01*
X2140485Y352908D01*
X2139710Y351658D01*
X2138780Y350825D01*
X2137540Y350200D01*
X2134440D01*
G01X2022685Y378300D02*
Y390800D01*
X2029815Y378300D01*
Y390800D01*
G01X2038650Y378300D02*
X2037410Y378508D01*
X2036325Y379341D01*
X2035395Y380592D01*
X2034775Y382050D01*
X2034465Y383717D01*
Y385383D01*
X2034775Y387050D01*
X2035395Y388508D01*
X2036325Y389758D01*
X2037410Y390592D01*
X2038650Y390800D01*
X2039890Y390592D01*
X2040975Y389758D01*
X2041905Y388508D01*
X2042525Y387050D01*
X2042835Y385383D01*
Y383717D01*
X2042525Y382050D01*
X2041905Y380592D01*
X2040975Y379341D01*
X2039890Y378508D01*
X2038650Y378300D01*
G01X2047485D02*
Y390800D01*
X2054615Y378300D01*
Y390800D01*
G01X2061435Y382467D02*
X2065465D01*
G01X2072750Y378300D02*
Y390800D01*
X2076470D01*
X2077710Y390175D01*
X2078640Y388717D01*
X2078950Y387050D01*
X2078640Y385383D01*
X2077865Y384133D01*
X2076470Y383508D01*
X2072750D01*
G01X2085150Y390800D02*
Y378300D01*
X2091350D01*
G01X2096775D02*
X2100650Y390800D01*
X2104525Y378300D01*
G01X2103130Y382675D02*
X2098170D01*
G01X2113050Y390800D02*
Y378300D01*
G01X2109485Y390800D02*
X2116615D01*
G01X2128550Y378300D02*
X2122350D01*
Y390800D01*
X2128550D01*
G01X2126070Y384758D02*
X2122350D01*
G01X2134440Y378300D02*
Y390800D01*
X2137540D01*
X2138780Y390175D01*
X2139710Y389342D01*
X2140485Y388092D01*
X2141105Y386633D01*
X2141260Y384550D01*
X2141105Y382467D01*
X2140485Y381008D01*
X2139710Y379758D01*
X2138780Y378925D01*
X2137540Y378300D01*
X2134440D01*
G01X2022685Y406400D02*
Y418900D01*
X2029815Y406400D01*
Y418900D01*
G01X2038650Y406400D02*
X2037410Y406608D01*
X2036325Y407441D01*
X2035395Y408692D01*
X2034775Y410150D01*
X2034465Y411817D01*
Y413483D01*
X2034775Y415150D01*
X2035395Y416608D01*
X2036325Y417858D01*
X2037410Y418692D01*
X2038650Y418900D01*
X2039890Y418692D01*
X2040975Y417858D01*
X2041905Y416608D01*
X2042525Y415150D01*
X2042835Y413483D01*
Y411817D01*
X2042525Y410150D01*
X2041905Y408692D01*
X2040975Y407441D01*
X2039890Y406608D01*
X2038650Y406400D01*
G01X2047485D02*
Y418900D01*
X2054615Y406400D01*
Y418900D01*
G01X2061435Y410567D02*
X2065465D01*
G01X2072750Y406400D02*
Y418900D01*
X2076470D01*
X2077710Y418275D01*
X2078640Y416817D01*
X2078950Y415150D01*
X2078640Y413483D01*
X2077865Y412233D01*
X2076470Y411608D01*
X2072750D01*
G01X2085150Y418900D02*
Y406400D01*
X2091350D01*
G01X2096775D02*
X2100650Y418900D01*
X2104525Y406400D01*
G01X2103130Y410775D02*
X2098170D01*
G01X2113050Y418900D02*
Y406400D01*
G01X2109485Y418900D02*
X2116615D01*
G01X2128550Y406400D02*
X2122350D01*
Y418900D01*
X2128550D01*
G01X2126070Y412858D02*
X2122350D01*
G01X2134440Y406400D02*
Y418900D01*
X2137540D01*
X2138780Y418275D01*
X2139710Y417442D01*
X2140485Y416192D01*
X2141105Y414733D01*
X2141260Y412650D01*
X2141105Y410567D01*
X2140485Y409108D01*
X2139710Y407858D01*
X2138780Y407025D01*
X2137540Y406400D01*
X2134440D01*
G01X2047950Y434500D02*
Y447000D01*
X2051670D01*
X2052910Y446375D01*
X2053840Y444917D01*
X2054150Y443250D01*
X2053840Y441583D01*
X2053065Y440333D01*
X2051670Y439708D01*
X2047950D01*
G01X2060350Y447000D02*
Y434500D01*
X2066550D01*
G01X2071975D02*
X2075850Y447000D01*
X2079725Y434500D01*
G01X2078330Y438875D02*
X2073370D01*
G01X2088250Y447000D02*
Y434500D01*
G01X2084685Y447000D02*
X2091815D01*
G01X2103750Y434500D02*
X2097550D01*
Y447000D01*
X2103750D01*
G01X2101270Y440958D02*
X2097550D01*
G01X2109640Y434500D02*
Y447000D01*
X2112740D01*
X2113980Y446375D01*
X2114910Y445542D01*
X2115685Y444292D01*
X2116305Y442833D01*
X2116460Y440750D01*
X2116305Y438667D01*
X2115685Y437208D01*
X2114910Y435958D01*
X2113980Y435125D01*
X2112740Y434500D01*
X2109640D01*
G01X2047950Y462600D02*
Y475100D01*
X2051670D01*
X2052910Y474475D01*
X2053840Y473017D01*
X2054150Y471350D01*
X2053840Y469683D01*
X2053065Y468433D01*
X2051670Y467808D01*
X2047950D01*
G01X2060350Y475100D02*
Y462600D01*
X2066550D01*
G01X2071975D02*
X2075850Y475100D01*
X2079725Y462600D01*
G01X2078330Y466975D02*
X2073370D01*
G01X2088250Y475100D02*
Y462600D01*
G01X2084685Y475100D02*
X2091815D01*
G01X2103750Y462600D02*
X2097550D01*
Y475100D01*
X2103750D01*
G01X2101270Y469058D02*
X2097550D01*
G01X2109640Y462600D02*
Y475100D01*
X2112740D01*
X2113980Y474475D01*
X2114910Y473642D01*
X2115685Y472392D01*
X2116305Y470933D01*
X2116460Y468850D01*
X2116305Y466767D01*
X2115685Y465308D01*
X2114910Y464058D01*
X2113980Y463225D01*
X2112740Y462600D01*
X2109640D01*
G01X2047950Y490700D02*
Y503200D01*
X2051670D01*
X2052910Y502575D01*
X2053840Y501117D01*
X2054150Y499450D01*
X2053840Y497783D01*
X2053065Y496533D01*
X2051670Y495908D01*
X2047950D01*
G01X2060350Y503200D02*
Y490700D01*
X2066550D01*
G01X2071975D02*
X2075850Y503200D01*
X2079725Y490700D01*
G01X2078330Y495075D02*
X2073370D01*
G01X2088250Y503200D02*
Y490700D01*
G01X2084685Y503200D02*
X2091815D01*
G01X2103750Y490700D02*
X2097550D01*
Y503200D01*
X2103750D01*
G01X2101270Y497158D02*
X2097550D01*
G01X2109640Y490700D02*
Y503200D01*
X2112740D01*
X2113980Y502575D01*
X2114910Y501742D01*
X2115685Y500492D01*
X2116305Y499033D01*
X2116460Y496950D01*
X2116305Y494867D01*
X2115685Y493408D01*
X2114910Y492158D01*
X2113980Y491325D01*
X2112740Y490700D01*
X2109640D01*
G01X2047950Y518800D02*
Y531300D01*
X2051670D01*
X2052910Y530675D01*
X2053840Y529217D01*
X2054150Y527550D01*
X2053840Y525883D01*
X2053065Y524633D01*
X2051670Y524008D01*
X2047950D01*
G01X2060350Y531300D02*
Y518800D01*
X2066550D01*
G01X2071975D02*
X2075850Y531300D01*
X2079725Y518800D01*
G01X2078330Y523175D02*
X2073370D01*
G01X2088250Y531300D02*
Y518800D01*
G01X2084685Y531300D02*
X2091815D01*
G01X2103750Y518800D02*
X2097550D01*
Y531300D01*
X2103750D01*
G01X2101270Y525258D02*
X2097550D01*
G01X2109640Y518800D02*
Y531300D01*
X2112740D01*
X2113980Y530675D01*
X2114910Y529842D01*
X2115685Y528592D01*
X2116305Y527133D01*
X2116460Y525050D01*
X2116305Y522967D01*
X2115685Y521508D01*
X2114910Y520258D01*
X2113980Y519425D01*
X2112740Y518800D01*
X2109640D01*
G01X2047950Y546900D02*
Y559400D01*
X2051670D01*
X2052910Y558775D01*
X2053840Y557317D01*
X2054150Y555650D01*
X2053840Y553983D01*
X2053065Y552733D01*
X2051670Y552108D01*
X2047950D01*
G01X2060350Y559400D02*
Y546900D01*
X2066550D01*
G01X2071975D02*
X2075850Y559400D01*
X2079725Y546900D01*
G01X2078330Y551275D02*
X2073370D01*
G01X2088250Y559400D02*
Y546900D01*
G01X2084685Y559400D02*
X2091815D01*
G01X2103750Y546900D02*
X2097550D01*
Y559400D01*
X2103750D01*
G01X2101270Y553358D02*
X2097550D01*
G01X2109640Y546900D02*
Y559400D01*
X2112740D01*
X2113980Y558775D01*
X2114910Y557942D01*
X2115685Y556692D01*
X2116305Y555233D01*
X2116460Y553150D01*
X2116305Y551067D01*
X2115685Y549608D01*
X2114910Y548358D01*
X2113980Y547525D01*
X2112740Y546900D01*
X2109640D01*
G01X2047950Y575000D02*
Y587500D01*
X2051670D01*
X2052910Y586875D01*
X2053840Y585417D01*
X2054150Y583750D01*
X2053840Y582083D01*
X2053065Y580833D01*
X2051670Y580208D01*
X2047950D01*
G01X2060350Y587500D02*
Y575000D01*
X2066550D01*
G01X2071975D02*
X2075850Y587500D01*
X2079725Y575000D01*
G01X2078330Y579375D02*
X2073370D01*
G01X2088250Y587500D02*
Y575000D01*
G01X2084685Y587500D02*
X2091815D01*
G01X2103750Y575000D02*
X2097550D01*
Y587500D01*
X2103750D01*
G01X2101270Y581458D02*
X2097550D01*
G01X2109640Y575000D02*
Y587500D01*
X2112740D01*
X2113980Y586875D01*
X2114910Y586042D01*
X2115685Y584792D01*
X2116305Y583333D01*
X2116460Y581250D01*
X2116305Y579167D01*
X2115685Y577708D01*
X2114910Y576458D01*
X2113980Y575625D01*
X2112740Y575000D01*
X2109640D01*
G01X2047950Y603100D02*
Y615600D01*
X2051670D01*
X2052910Y614975D01*
X2053840Y613517D01*
X2054150Y611850D01*
X2053840Y610183D01*
X2053065Y608933D01*
X2051670Y608308D01*
X2047950D01*
G01X2060350Y615600D02*
Y603100D01*
X2066550D01*
G01X2071975D02*
X2075850Y615600D01*
X2079725Y603100D01*
G01X2078330Y607475D02*
X2073370D01*
G01X2088250Y615600D02*
Y603100D01*
G01X2084685Y615600D02*
X2091815D01*
G01X2103750Y603100D02*
X2097550D01*
Y615600D01*
X2103750D01*
G01X2101270Y609558D02*
X2097550D01*
G01X2109640Y603100D02*
Y615600D01*
X2112740D01*
X2113980Y614975D01*
X2114910Y614142D01*
X2115685Y612892D01*
X2116305Y611433D01*
X2116460Y609350D01*
X2116305Y607267D01*
X2115685Y605808D01*
X2114910Y604558D01*
X2113980Y603725D01*
X2112740Y603100D01*
X2109640D01*
G01X2047950Y631200D02*
Y643700D01*
X2051670D01*
X2052910Y643075D01*
X2053840Y641617D01*
X2054150Y639950D01*
X2053840Y638283D01*
X2053065Y637033D01*
X2051670Y636408D01*
X2047950D01*
G01X2060350Y643700D02*
Y631200D01*
X2066550D01*
G01X2071975D02*
X2075850Y643700D01*
X2079725Y631200D01*
G01X2078330Y635575D02*
X2073370D01*
G01X2088250Y643700D02*
Y631200D01*
G01X2084685Y643700D02*
X2091815D01*
G01X2103750Y631200D02*
X2097550D01*
Y643700D01*
X2103750D01*
G01X2101270Y637658D02*
X2097550D01*
G01X2109640Y631200D02*
Y643700D01*
X2112740D01*
X2113980Y643075D01*
X2114910Y642242D01*
X2115685Y640992D01*
X2116305Y639533D01*
X2116460Y637450D01*
X2116305Y635367D01*
X2115685Y633908D01*
X2114910Y632658D01*
X2113980Y631825D01*
X2112740Y631200D01*
X2109640D01*
G01X2047950Y659300D02*
Y671800D01*
X2051670D01*
X2052910Y671175D01*
X2053840Y669717D01*
X2054150Y668050D01*
X2053840Y666383D01*
X2053065Y665133D01*
X2051670Y664508D01*
X2047950D01*
G01X2060350Y671800D02*
Y659300D01*
X2066550D01*
G01X2071975D02*
X2075850Y671800D01*
X2079725Y659300D01*
G01X2078330Y663675D02*
X2073370D01*
G01X2088250Y671800D02*
Y659300D01*
G01X2084685Y671800D02*
X2091815D01*
G01X2103750Y659300D02*
X2097550D01*
Y671800D01*
X2103750D01*
G01X2101270Y665758D02*
X2097550D01*
G01X2109640Y659300D02*
Y671800D01*
X2112740D01*
X2113980Y671175D01*
X2114910Y670342D01*
X2115685Y669092D01*
X2116305Y667633D01*
X2116460Y665550D01*
X2116305Y663467D01*
X2115685Y662008D01*
X2114910Y660758D01*
X2113980Y659925D01*
X2112740Y659300D01*
X2109640D01*
G01X2047950Y687400D02*
Y699900D01*
X2051670D01*
X2052910Y699275D01*
X2053840Y697817D01*
X2054150Y696150D01*
X2053840Y694483D01*
X2053065Y693233D01*
X2051670Y692608D01*
X2047950D01*
G01X2060350Y699900D02*
Y687400D01*
X2066550D01*
G01X2071975D02*
X2075850Y699900D01*
X2079725Y687400D01*
G01X2078330Y691775D02*
X2073370D01*
G01X2088250Y699900D02*
Y687400D01*
G01X2084685Y699900D02*
X2091815D01*
G01X2103750Y687400D02*
X2097550D01*
Y699900D01*
X2103750D01*
G01X2101270Y693858D02*
X2097550D01*
G01X2109640Y687400D02*
Y699900D01*
X2112740D01*
X2113980Y699275D01*
X2114910Y698442D01*
X2115685Y697192D01*
X2116305Y695733D01*
X2116460Y693650D01*
X2116305Y691567D01*
X2115685Y690108D01*
X2114910Y688858D01*
X2113980Y688025D01*
X2112740Y687400D01*
X2109640D01*
G01X2047950Y715500D02*
Y728000D01*
X2051670D01*
X2052910Y727375D01*
X2053840Y725917D01*
X2054150Y724250D01*
X2053840Y722583D01*
X2053065Y721333D01*
X2051670Y720708D01*
X2047950D01*
G01X2060350Y728000D02*
Y715500D01*
X2066550D01*
G01X2071975D02*
X2075850Y728000D01*
X2079725Y715500D01*
G01X2078330Y719875D02*
X2073370D01*
G01X2088250Y728000D02*
Y715500D01*
G01X2084685Y728000D02*
X2091815D01*
G01X2103750Y715500D02*
X2097550D01*
Y728000D01*
X2103750D01*
G01X2101270Y721958D02*
X2097550D01*
G01X2109640Y715500D02*
Y728000D01*
X2112740D01*
X2113980Y727375D01*
X2114910Y726542D01*
X2115685Y725292D01*
X2116305Y723833D01*
X2116460Y721750D01*
X2116305Y719667D01*
X2115685Y718208D01*
X2114910Y716958D01*
X2113980Y716125D01*
X2112740Y715500D01*
X2109640D01*
G01X2047950Y743600D02*
Y756100D01*
X2051670D01*
X2052910Y755475D01*
X2053840Y754017D01*
X2054150Y752350D01*
X2053840Y750683D01*
X2053065Y749433D01*
X2051670Y748808D01*
X2047950D01*
G01X2060350Y756100D02*
Y743600D01*
X2066550D01*
G01X2071975D02*
X2075850Y756100D01*
X2079725Y743600D01*
G01X2078330Y747975D02*
X2073370D01*
G01X2088250Y756100D02*
Y743600D01*
G01X2084685Y756100D02*
X2091815D01*
G01X2103750Y743600D02*
X2097550D01*
Y756100D01*
X2103750D01*
G01X2101270Y750058D02*
X2097550D01*
G01X2109640Y743600D02*
Y756100D01*
X2112740D01*
X2113980Y755475D01*
X2114910Y754642D01*
X2115685Y753392D01*
X2116305Y751933D01*
X2116460Y749850D01*
X2116305Y747767D01*
X2115685Y746308D01*
X2114910Y745058D01*
X2113980Y744225D01*
X2112740Y743600D01*
X2109640D01*
G01X2047950Y771700D02*
Y784200D01*
X2051670D01*
X2052910Y783575D01*
X2053840Y782117D01*
X2054150Y780450D01*
X2053840Y778783D01*
X2053065Y777533D01*
X2051670Y776908D01*
X2047950D01*
G01X2060350Y784200D02*
Y771700D01*
X2066550D01*
G01X2071975D02*
X2075850Y784200D01*
X2079725Y771700D01*
G01X2078330Y776075D02*
X2073370D01*
G01X2088250Y784200D02*
Y771700D01*
G01X2084685Y784200D02*
X2091815D01*
G01X2103750Y771700D02*
X2097550D01*
Y784200D01*
X2103750D01*
G01X2101270Y778158D02*
X2097550D01*
G01X2109640Y771700D02*
Y784200D01*
X2112740D01*
X2113980Y783575D01*
X2114910Y782742D01*
X2115685Y781492D01*
X2116305Y780033D01*
X2116460Y777950D01*
X2116305Y775867D01*
X2115685Y774408D01*
X2114910Y773158D01*
X2113980Y772325D01*
X2112740Y771700D01*
X2109640D01*
G01X2047950Y799800D02*
Y812300D01*
X2051670D01*
X2052910Y811675D01*
X2053840Y810217D01*
X2054150Y808550D01*
X2053840Y806883D01*
X2053065Y805633D01*
X2051670Y805008D01*
X2047950D01*
G01X2060350Y812300D02*
Y799800D01*
X2066550D01*
G01X2071975D02*
X2075850Y812300D01*
X2079725Y799800D01*
G01X2078330Y804175D02*
X2073370D01*
G01X2088250Y812300D02*
Y799800D01*
G01X2084685Y812300D02*
X2091815D01*
G01X2103750Y799800D02*
X2097550D01*
Y812300D01*
X2103750D01*
G01X2101270Y806258D02*
X2097550D01*
G01X2109640Y799800D02*
Y812300D01*
X2112740D01*
X2113980Y811675D01*
X2114910Y810842D01*
X2115685Y809592D01*
X2116305Y808133D01*
X2116460Y806050D01*
X2116305Y803967D01*
X2115685Y802508D01*
X2114910Y801258D01*
X2113980Y800425D01*
X2112740Y799800D01*
X2109640D01*
G01X2047950Y827900D02*
Y840400D01*
X2051670D01*
X2052910Y839775D01*
X2053840Y838317D01*
X2054150Y836650D01*
X2053840Y834983D01*
X2053065Y833733D01*
X2051670Y833108D01*
X2047950D01*
G01X2060350Y840400D02*
Y827900D01*
X2066550D01*
G01X2071975D02*
X2075850Y840400D01*
X2079725Y827900D01*
G01X2078330Y832275D02*
X2073370D01*
G01X2088250Y840400D02*
Y827900D01*
G01X2084685Y840400D02*
X2091815D01*
G01X2103750Y827900D02*
X2097550D01*
Y840400D01*
X2103750D01*
G01X2101270Y834358D02*
X2097550D01*
G01X2109640Y827900D02*
Y840400D01*
X2112740D01*
X2113980Y839775D01*
X2114910Y838942D01*
X2115685Y837692D01*
X2116305Y836233D01*
X2116460Y834150D01*
X2116305Y832067D01*
X2115685Y830608D01*
X2114910Y829358D01*
X2113980Y828525D01*
X2112740Y827900D01*
X2109640D01*
G01X2047950Y856000D02*
Y868500D01*
X2051670D01*
X2052910Y867875D01*
X2053840Y866417D01*
X2054150Y864750D01*
X2053840Y863083D01*
X2053065Y861833D01*
X2051670Y861208D01*
X2047950D01*
G01X2060350Y868500D02*
Y856000D01*
X2066550D01*
G01X2071975D02*
X2075850Y868500D01*
X2079725Y856000D01*
G01X2078330Y860375D02*
X2073370D01*
G01X2088250Y868500D02*
Y856000D01*
G01X2084685Y868500D02*
X2091815D01*
G01X2103750Y856000D02*
X2097550D01*
Y868500D01*
X2103750D01*
G01X2101270Y862458D02*
X2097550D01*
G01X2109640Y856000D02*
Y868500D01*
X2112740D01*
X2113980Y867875D01*
X2114910Y867042D01*
X2115685Y865792D01*
X2116305Y864333D01*
X2116460Y862250D01*
X2116305Y860167D01*
X2115685Y858708D01*
X2114910Y857458D01*
X2113980Y856625D01*
X2112740Y856000D01*
X2109640D01*
G01X2047950Y885650D02*
Y898150D01*
X2051670D01*
X2052910Y897525D01*
X2053840Y896067D01*
X2054150Y894400D01*
X2053840Y892733D01*
X2053065Y891483D01*
X2051670Y890858D01*
X2047950D01*
G01X2060350Y898150D02*
Y885650D01*
X2066550D01*
G01X2071975D02*
X2075850Y898150D01*
X2079725Y885650D01*
G01X2078330Y890025D02*
X2073370D01*
G01X2088250Y898150D02*
Y885650D01*
G01X2084685Y898150D02*
X2091815D01*
G01X2103750Y885650D02*
X2097550D01*
Y898150D01*
X2103750D01*
G01X2101270Y892108D02*
X2097550D01*
G01X2109640Y885650D02*
Y898150D01*
X2112740D01*
X2113980Y897525D01*
X2114910Y896692D01*
X2115685Y895442D01*
X2116305Y893983D01*
X2116460Y891900D01*
X2116305Y889817D01*
X2115685Y888358D01*
X2114910Y887108D01*
X2113980Y886275D01*
X2112740Y885650D01*
X2109640D01*
G01X2145600Y904400D02*
Y61400D01*
G01X2171950Y771700D02*
Y784200D01*
X2170090Y781700D01*
G01Y771700D02*
X2173810D01*
G01X2181405Y776908D02*
X2182490Y778367D01*
X2183420Y779200D01*
X2184660Y779617D01*
X2185745Y779200D01*
X2186520Y778367D01*
X2187140Y777117D01*
X2187295Y775658D01*
X2187140Y774408D01*
X2186520Y773158D01*
X2185590Y772117D01*
X2184505Y771700D01*
X2183265Y772117D01*
X2182180Y773366D01*
X2181560Y775242D01*
X2181405Y777325D01*
X2181715Y780033D01*
X2182180Y781492D01*
X2182955Y782950D01*
X2184040Y783992D01*
X2185125Y784200D01*
X2186210Y783783D01*
X2186985Y782742D01*
G01X2198610Y771700D02*
Y784200D01*
X2192875Y775242D01*
X2200625D01*
G01X2171640Y799800D02*
X2171950Y802508D01*
X2172415Y804800D01*
X2173035Y806883D01*
X2173810Y809175D01*
X2175050Y812300D01*
X2168850D01*
G01X2181405Y805008D02*
X2182490Y806467D01*
X2183420Y807300D01*
X2184660Y807717D01*
X2185745Y807300D01*
X2186520Y806467D01*
X2187140Y805217D01*
X2187295Y803758D01*
X2187140Y802508D01*
X2186520Y801258D01*
X2185590Y800217D01*
X2184505Y799800D01*
X2183265Y800217D01*
X2182180Y801466D01*
X2181560Y803342D01*
X2181405Y805425D01*
X2181715Y808133D01*
X2182180Y809592D01*
X2182955Y811050D01*
X2184040Y812092D01*
X2185125Y812300D01*
X2186210Y811883D01*
X2186985Y810842D01*
G01X2193805Y810217D02*
X2194735Y811466D01*
X2195820Y812092D01*
X2197060Y812300D01*
X2198610Y811883D01*
X2199695Y810842D01*
X2200005Y809592D01*
X2199850Y808341D01*
X2199230Y807300D01*
X2196130Y805217D01*
X2194735Y803758D01*
X2193805Y801675D01*
X2193495Y799800D01*
X2200005D01*
G01X2162805Y838317D02*
X2163735Y839566D01*
X2164820Y840192D01*
X2166060Y840400D01*
X2167610Y839983D01*
X2168695Y838942D01*
X2169005Y837692D01*
X2168850Y836441D01*
X2168230Y835400D01*
X2165130Y833317D01*
X2163735Y831858D01*
X2162805Y829775D01*
X2162495Y827900D01*
X2169005D01*
G01X2178150D02*
Y840400D01*
X2176290Y837900D01*
G01Y827900D02*
X2180010D01*
G01X2192410D02*
Y840400D01*
X2186675Y831442D01*
X2194425D01*
G01X2202950Y840400D02*
X2201710Y839983D01*
X2200780Y838942D01*
X2200160Y837692D01*
X2199695Y836025D01*
X2199540Y834150D01*
X2199695Y832275D01*
X2200160Y830608D01*
X2200780Y829358D01*
X2201710Y828317D01*
X2202950Y827900D01*
X2204190Y828317D01*
X2205120Y829358D01*
X2205740Y830608D01*
X2206205Y832275D01*
X2206360Y834150D01*
X2206205Y836025D01*
X2205740Y837692D01*
X2205120Y838942D01*
X2204190Y839983D01*
X2202950Y840400D01*
G01X2165750Y856000D02*
Y868500D01*
X2163890Y866000D01*
G01Y856000D02*
X2167610D01*
G01X2174740Y857875D02*
X2175670Y856833D01*
X2176755Y856208D01*
X2178150Y856000D01*
X2179545Y856417D01*
X2180630Y857250D01*
X2181405Y858708D01*
X2181560Y860375D01*
X2181250Y862042D01*
X2180475Y863083D01*
X2179390Y863917D01*
X2178305Y864125D01*
X2177220Y863917D01*
X2175825Y863083D01*
X2176290Y868500D01*
X2180475D01*
G01X2190240Y856000D02*
X2190550Y858708D01*
X2191015Y861000D01*
X2191635Y863083D01*
X2192410Y865375D01*
X2193650Y868500D01*
X2187450D01*
G01X2204810Y856000D02*
Y868500D01*
X2199075Y859542D01*
X2206825D01*
G01X2171950Y885650D02*
X2170710Y885858D01*
X2169625Y886691D01*
X2168695Y887942D01*
X2168075Y889400D01*
X2167765Y891067D01*
Y892733D01*
X2168075Y894400D01*
X2168695Y895858D01*
X2169625Y897108D01*
X2170710Y897942D01*
X2171950Y898150D01*
X2173190Y897942D01*
X2174275Y897108D01*
X2175205Y895858D01*
X2175825Y894400D01*
X2176135Y892733D01*
Y891067D01*
X2175825Y889400D01*
X2175205Y887942D01*
X2174275Y886691D01*
X2173190Y885858D01*
X2171950Y885650D01*
G01X2173190Y888983D02*
X2175050Y885650D01*
G01X2184350Y898150D02*
Y885650D01*
G01X2180785Y898150D02*
X2187915D01*
G01X2196750Y885650D02*
Y891275D01*
X2193650Y898150D01*
G01X2199850D02*
X2196750Y891275D01*
G01X2186210Y69200D02*
Y81700D01*
X2180475Y72742D01*
X2188225D01*
G01X2186210Y97300D02*
Y109800D01*
X2180475Y100842D01*
X2188225D01*
G01X2181405Y135817D02*
X2182335Y137066D01*
X2183420Y137692D01*
X2184660Y137900D01*
X2186210Y137483D01*
X2187295Y136442D01*
X2187605Y135192D01*
X2187450Y133941D01*
X2186830Y132900D01*
X2183730Y130817D01*
X2182335Y129358D01*
X2181405Y127275D01*
X2181095Y125400D01*
X2187605D01*
G01X2178150Y153500D02*
Y166000D01*
X2176290Y163500D01*
G01Y153500D02*
X2180010D01*
G01X2190550Y166000D02*
X2189310Y165583D01*
X2188380Y164542D01*
X2187760Y163292D01*
X2187295Y161625D01*
X2187140Y159750D01*
X2187295Y157875D01*
X2187760Y156208D01*
X2188380Y154958D01*
X2189310Y153917D01*
X2190550Y153500D01*
X2191790Y153917D01*
X2192720Y154958D01*
X2193340Y156208D01*
X2193805Y157875D01*
X2193960Y159750D01*
X2193805Y161625D01*
X2193340Y163292D01*
X2192720Y164542D01*
X2191790Y165583D01*
X2190550Y166000D01*
G01X2181405Y192017D02*
X2182335Y193266D01*
X2183420Y193892D01*
X2184660Y194100D01*
X2186210Y193683D01*
X2187295Y192642D01*
X2187605Y191392D01*
X2187450Y190141D01*
X2186830Y189100D01*
X2183730Y187017D01*
X2182335Y185558D01*
X2181405Y183475D01*
X2181095Y181600D01*
X2187605D01*
G01X2184350Y209700D02*
X2185435Y209908D01*
X2186675Y210533D01*
X2187450Y211575D01*
X2187760Y213033D01*
X2187450Y214491D01*
X2186520Y215742D01*
X2185125Y216367D01*
X2183575D01*
X2182645Y216783D01*
X2181870Y217825D01*
X2181560Y219283D01*
X2182025Y220742D01*
X2183110Y221783D01*
X2184350Y222200D01*
X2185590Y221783D01*
X2186675Y220742D01*
X2187140Y219283D01*
X2186830Y217825D01*
X2186055Y216783D01*
X2185125Y216367D01*
X2183575D01*
X2182180Y215742D01*
X2181250Y214491D01*
X2180940Y213033D01*
X2181250Y211575D01*
X2182025Y210533D01*
X2183265Y209908D01*
X2184350Y209700D01*
G01X2186210Y237800D02*
Y250300D01*
X2180475Y241342D01*
X2188225D01*
G01X2181405Y276317D02*
X2182335Y277566D01*
X2183420Y278192D01*
X2184660Y278400D01*
X2186210Y277983D01*
X2187295Y276942D01*
X2187605Y275692D01*
X2187450Y274441D01*
X2186830Y273400D01*
X2183730Y271317D01*
X2182335Y269858D01*
X2181405Y267775D01*
X2181095Y265900D01*
X2187605D01*
G01X2184350Y294000D02*
Y306500D01*
X2182490Y304000D01*
G01Y294000D02*
X2186210D01*
G01X2181405Y332517D02*
X2182335Y333766D01*
X2183420Y334392D01*
X2184660Y334600D01*
X2186210Y334183D01*
X2187295Y333142D01*
X2187605Y331892D01*
X2187450Y330641D01*
X2186830Y329600D01*
X2183730Y327517D01*
X2182335Y326058D01*
X2181405Y323975D01*
X2181095Y322100D01*
X2187605D01*
G01X2181405Y360617D02*
X2182335Y361866D01*
X2183420Y362492D01*
X2184660Y362700D01*
X2186210Y362283D01*
X2187295Y361242D01*
X2187605Y359992D01*
X2187450Y358741D01*
X2186830Y357700D01*
X2183730Y355617D01*
X2182335Y354158D01*
X2181405Y352075D01*
X2181095Y350200D01*
X2187605D01*
G01X2184350Y378300D02*
Y390800D01*
X2182490Y388300D01*
G01Y378300D02*
X2186210D01*
G01X2181405Y416817D02*
X2182335Y418066D01*
X2183420Y418692D01*
X2184660Y418900D01*
X2186210Y418483D01*
X2187295Y417442D01*
X2187605Y416192D01*
X2187450Y414941D01*
X2186830Y413900D01*
X2183730Y411817D01*
X2182335Y410358D01*
X2181405Y408275D01*
X2181095Y406400D01*
X2187605D01*
G01X2186210Y434500D02*
Y447000D01*
X2180475Y438042D01*
X2188225D01*
G01X2181405Y473017D02*
X2182335Y474266D01*
X2183420Y474892D01*
X2184660Y475100D01*
X2186210Y474683D01*
X2187295Y473642D01*
X2187605Y472392D01*
X2187450Y471141D01*
X2186830Y470100D01*
X2183730Y468017D01*
X2182335Y466558D01*
X2181405Y464475D01*
X2181095Y462600D01*
X2187605D01*
G01X2181405Y501117D02*
X2182335Y502366D01*
X2183420Y502992D01*
X2184660Y503200D01*
X2186210Y502783D01*
X2187295Y501742D01*
X2187605Y500492D01*
X2187450Y499241D01*
X2186830Y498200D01*
X2183730Y496117D01*
X2182335Y494658D01*
X2181405Y492575D01*
X2181095Y490700D01*
X2187605D01*
G01X2180940Y520675D02*
X2181870Y519633D01*
X2182955Y519008D01*
X2184350Y518800D01*
X2185745Y519217D01*
X2186830Y520050D01*
X2187605Y521508D01*
X2187760Y523175D01*
X2187450Y524842D01*
X2186675Y525883D01*
X2185590Y526717D01*
X2184505Y526925D01*
X2183420Y526717D01*
X2182025Y525883D01*
X2182490Y531300D01*
X2186675D01*
G01X2175205Y557317D02*
X2176135Y558566D01*
X2177220Y559192D01*
X2178460Y559400D01*
X2180010Y558983D01*
X2181095Y557942D01*
X2181405Y556692D01*
X2181250Y555441D01*
X2180630Y554400D01*
X2177530Y552317D01*
X2176135Y550858D01*
X2175205Y548775D01*
X2174895Y546900D01*
X2181405D01*
G01X2190550Y559400D02*
X2189310Y558983D01*
X2188380Y557942D01*
X2187760Y556692D01*
X2187295Y555025D01*
X2187140Y553150D01*
X2187295Y551275D01*
X2187760Y549608D01*
X2188380Y548358D01*
X2189310Y547317D01*
X2190550Y546900D01*
X2191790Y547317D01*
X2192720Y548358D01*
X2193340Y549608D01*
X2193805Y551275D01*
X2193960Y553150D01*
X2193805Y555025D01*
X2193340Y556692D01*
X2192720Y557942D01*
X2191790Y558983D01*
X2190550Y559400D01*
G01X2180940Y577500D02*
X2181870Y576041D01*
X2183110Y575208D01*
X2184505Y575000D01*
X2185745Y575208D01*
X2186985Y576250D01*
X2187760Y577500D01*
X2187915Y578750D01*
X2187605Y580208D01*
X2186520Y581250D01*
X2185435Y581667D01*
X2184040D01*
G01X2185435D02*
X2186365Y582292D01*
X2187140Y583333D01*
X2187450Y584583D01*
X2187140Y585833D01*
X2186365Y586875D01*
X2184970Y587500D01*
X2183575Y587292D01*
X2182180Y586458D01*
G01X2178150Y603100D02*
Y615600D01*
X2176290Y613100D01*
G01Y603100D02*
X2180010D01*
G01X2190550D02*
X2191635Y603308D01*
X2192875Y603933D01*
X2193650Y604975D01*
X2193960Y606433D01*
X2193650Y607891D01*
X2192720Y609142D01*
X2191325Y609767D01*
X2189775D01*
X2188845Y610183D01*
X2188070Y611225D01*
X2187760Y612683D01*
X2188225Y614142D01*
X2189310Y615183D01*
X2190550Y615600D01*
X2191790Y615183D01*
X2192875Y614142D01*
X2193340Y612683D01*
X2193030Y611225D01*
X2192255Y610183D01*
X2191325Y609767D01*
X2189775D01*
X2188380Y609142D01*
X2187450Y607891D01*
X2187140Y606433D01*
X2187450Y604975D01*
X2188225Y603933D01*
X2189465Y603308D01*
X2190550Y603100D01*
G01X2186210Y631200D02*
Y643700D01*
X2180475Y634742D01*
X2188225D01*
G01X2178150Y659300D02*
Y671800D01*
X2176290Y669300D01*
G01Y659300D02*
X2180010D01*
G01X2187605Y669717D02*
X2188535Y670966D01*
X2189620Y671592D01*
X2190860Y671800D01*
X2192410Y671383D01*
X2193495Y670342D01*
X2193805Y669092D01*
X2193650Y667841D01*
X2193030Y666800D01*
X2189930Y664717D01*
X2188535Y663258D01*
X2187605Y661175D01*
X2187295Y659300D01*
X2193805D01*
G01X2178150Y687400D02*
Y699900D01*
X2176290Y697400D01*
G01Y687400D02*
X2180010D01*
G01X2190240D02*
X2190550Y690108D01*
X2191015Y692400D01*
X2191635Y694483D01*
X2192410Y696775D01*
X2193650Y699900D01*
X2187450D01*
G01X2181405Y720708D02*
X2182490Y722167D01*
X2183420Y723000D01*
X2184660Y723417D01*
X2185745Y723000D01*
X2186520Y722167D01*
X2187140Y720917D01*
X2187295Y719458D01*
X2187140Y718208D01*
X2186520Y716958D01*
X2185590Y715917D01*
X2184505Y715500D01*
X2183265Y715917D01*
X2182180Y717166D01*
X2181560Y719042D01*
X2181405Y721125D01*
X2181715Y723833D01*
X2182180Y725292D01*
X2182955Y726750D01*
X2184040Y727792D01*
X2185125Y728000D01*
X2186210Y727583D01*
X2186985Y726542D01*
G01X2180940Y746100D02*
X2181870Y744641D01*
X2183110Y743808D01*
X2184505Y743600D01*
X2185745Y743808D01*
X2186985Y744850D01*
X2187760Y746100D01*
X2187915Y747350D01*
X2187605Y748808D01*
X2186520Y749850D01*
X2185435Y750267D01*
X2184040D01*
G01X2185435D02*
X2186365Y750892D01*
X2187140Y751933D01*
X2187450Y753183D01*
X2187140Y754433D01*
X2186365Y755475D01*
X2184970Y756100D01*
X2183575Y755892D01*
X2182180Y755058D01*
G01X994518Y227644D02*
Y231644D01*
X993718Y230844D01*
G01Y227644D02*
X995318D01*
G01X999118D02*
X999585Y227711D01*
X1000118Y227911D01*
X1000451Y228244D01*
X1000585Y228711D01*
X1000451Y229177D01*
X1000051Y229577D01*
X999451Y229777D01*
X998785D01*
X998385Y229911D01*
X998051Y230244D01*
X997918Y230711D01*
X998118Y231177D01*
X998585Y231511D01*
X999118Y231644D01*
X999651Y231511D01*
X1000118Y231177D01*
X1000318Y230711D01*
X1000185Y230244D01*
X999851Y229911D01*
X999451Y229777D01*
X998785D01*
X998185Y229577D01*
X997785Y229177D01*
X997651Y228711D01*
X997785Y228244D01*
X998118Y227911D01*
X998651Y227711D01*
X999118Y227644D01*
G01X1002585Y228111D02*
X1003051Y227777D01*
X1003585Y227644D01*
X1004118Y227777D01*
X1004585Y228177D01*
X1004918Y228777D01*
X1005051Y229377D01*
Y230111D01*
X1004918Y230711D01*
X1004585Y231244D01*
X1004185Y231511D01*
X1003718Y231644D01*
X1003185Y231511D01*
X1002785Y231244D01*
X1002518Y230844D01*
X1002385Y230311D01*
X1002518Y229844D01*
X1002851Y229377D01*
X1003251Y229111D01*
X1003718Y229044D01*
X1004251Y229177D01*
X1004651Y229511D01*
X1005051Y230111D01*
G01X1006918Y227644D02*
X1009718Y231644D01*
G01X1006918D02*
X1009718Y227644D01*
G01X1012918D02*
Y231644D01*
X1012118Y230844D01*
G01Y227644D02*
X1013718D01*
G01X1016251Y230977D02*
X1016651Y231377D01*
X1017118Y231577D01*
X1017651Y231644D01*
X1018318Y231511D01*
X1018785Y231177D01*
X1018918Y230777D01*
X1018851Y230377D01*
X1018585Y230044D01*
X1017251Y229377D01*
X1016651Y228911D01*
X1016251Y228244D01*
X1016118Y227644D01*
X1018918D01*
G01X1020851Y229311D02*
X1021318Y229777D01*
X1021718Y230044D01*
X1022251Y230177D01*
X1022718Y230044D01*
X1023051Y229777D01*
X1023318Y229377D01*
X1023385Y228911D01*
X1023318Y228511D01*
X1023051Y228111D01*
X1022651Y227777D01*
X1022185Y227644D01*
X1021651Y227777D01*
X1021185Y228177D01*
X1020918Y228777D01*
X1020851Y229444D01*
X1020985Y230311D01*
X1021185Y230777D01*
X1021518Y231244D01*
X1021985Y231577D01*
X1022451Y231644D01*
X1022918Y231511D01*
X1023251Y231177D01*
G01X994518Y394967D02*
Y398967D01*
X993718Y398167D01*
G01Y394967D02*
X995318D01*
G01X999118D02*
X999585Y395034D01*
X1000118Y395234D01*
X1000451Y395567D01*
X1000585Y396034D01*
X1000451Y396500D01*
X1000051Y396900D01*
X999451Y397100D01*
X998785D01*
X998385Y397234D01*
X998051Y397567D01*
X997918Y398034D01*
X998118Y398500D01*
X998585Y398834D01*
X999118Y398967D01*
X999651Y398834D01*
X1000118Y398500D01*
X1000318Y398034D01*
X1000185Y397567D01*
X999851Y397234D01*
X999451Y397100D01*
X998785D01*
X998185Y396900D01*
X997785Y396500D01*
X997651Y396034D01*
X997785Y395567D01*
X998118Y395234D01*
X998651Y395034D01*
X999118Y394967D01*
G01X1002585Y395434D02*
X1003051Y395100D01*
X1003585Y394967D01*
X1004118Y395100D01*
X1004585Y395500D01*
X1004918Y396100D01*
X1005051Y396700D01*
Y397434D01*
X1004918Y398034D01*
X1004585Y398567D01*
X1004185Y398834D01*
X1003718Y398967D01*
X1003185Y398834D01*
X1002785Y398567D01*
X1002518Y398167D01*
X1002385Y397634D01*
X1002518Y397167D01*
X1002851Y396700D01*
X1003251Y396434D01*
X1003718Y396367D01*
X1004251Y396500D01*
X1004651Y396834D01*
X1005051Y397434D01*
G01X1006918Y394967D02*
X1009718Y398967D01*
G01X1006918D02*
X1009718Y394967D01*
G01X1012918D02*
Y398967D01*
X1012118Y398167D01*
G01Y394967D02*
X1013718D01*
G01X1016251Y398300D02*
X1016651Y398700D01*
X1017118Y398900D01*
X1017651Y398967D01*
X1018318Y398834D01*
X1018785Y398500D01*
X1018918Y398100D01*
X1018851Y397700D01*
X1018585Y397367D01*
X1017251Y396700D01*
X1016651Y396234D01*
X1016251Y395567D01*
X1016118Y394967D01*
X1018918D01*
G01X1020851Y396634D02*
X1021318Y397100D01*
X1021718Y397367D01*
X1022251Y397500D01*
X1022718Y397367D01*
X1023051Y397100D01*
X1023318Y396700D01*
X1023385Y396234D01*
X1023318Y395834D01*
X1023051Y395434D01*
X1022651Y395100D01*
X1022185Y394967D01*
X1021651Y395100D01*
X1021185Y395500D01*
X1020918Y396100D01*
X1020851Y396767D01*
X1020985Y397634D01*
X1021185Y398100D01*
X1021518Y398567D01*
X1021985Y398900D01*
X1022451Y398967D01*
X1022918Y398834D01*
X1023251Y398500D01*
G01X1213416Y139061D02*
Y143061D01*
X1212616Y142261D01*
G01Y139061D02*
X1214216D01*
G01X1218016D02*
X1218483Y139128D01*
X1219016Y139328D01*
X1219349Y139661D01*
X1219483Y140128D01*
X1219349Y140594D01*
X1218949Y140994D01*
X1218349Y141194D01*
X1217683D01*
X1217283Y141328D01*
X1216949Y141661D01*
X1216816Y142128D01*
X1217016Y142594D01*
X1217483Y142928D01*
X1218016Y143061D01*
X1218549Y142928D01*
X1219016Y142594D01*
X1219216Y142128D01*
X1219083Y141661D01*
X1218749Y141328D01*
X1218349Y141194D01*
X1217683D01*
X1217083Y140994D01*
X1216683Y140594D01*
X1216549Y140128D01*
X1216683Y139661D01*
X1217016Y139328D01*
X1217549Y139128D01*
X1218016Y139061D01*
G01X1221483Y139528D02*
X1221949Y139194D01*
X1222483Y139061D01*
X1223016Y139194D01*
X1223483Y139594D01*
X1223816Y140194D01*
X1223949Y140794D01*
Y141528D01*
X1223816Y142128D01*
X1223483Y142661D01*
X1223083Y142928D01*
X1222616Y143061D01*
X1222083Y142928D01*
X1221683Y142661D01*
X1221416Y142261D01*
X1221283Y141728D01*
X1221416Y141261D01*
X1221749Y140794D01*
X1222149Y140528D01*
X1222616Y140461D01*
X1223149Y140594D01*
X1223549Y140928D01*
X1223949Y141528D01*
G01X1225816Y139061D02*
X1228616Y143061D01*
G01X1225816D02*
X1228616Y139061D01*
G01X1231816D02*
Y143061D01*
X1231016Y142261D01*
G01Y139061D02*
X1232616D01*
G01X1235149Y142394D02*
X1235549Y142794D01*
X1236016Y142994D01*
X1236549Y143061D01*
X1237216Y142928D01*
X1237683Y142594D01*
X1237816Y142194D01*
X1237749Y141794D01*
X1237483Y141461D01*
X1236149Y140794D01*
X1235549Y140328D01*
X1235149Y139661D01*
X1235016Y139061D01*
X1237816D01*
G01X1239749Y140728D02*
X1240216Y141194D01*
X1240616Y141461D01*
X1241149Y141594D01*
X1241616Y141461D01*
X1241949Y141194D01*
X1242216Y140794D01*
X1242283Y140328D01*
X1242216Y139928D01*
X1241949Y139528D01*
X1241549Y139194D01*
X1241083Y139061D01*
X1240549Y139194D01*
X1240083Y139594D01*
X1239816Y140194D01*
X1239749Y140861D01*
X1239883Y141728D01*
X1240083Y142194D01*
X1240416Y142661D01*
X1240883Y142994D01*
X1241349Y143061D01*
X1241816Y142928D01*
X1242149Y142594D01*
G01X1213415Y394967D02*
Y398967D01*
X1212615Y398167D01*
G01Y394967D02*
X1214215D01*
G01X1218015D02*
X1218482Y395034D01*
X1219015Y395234D01*
X1219348Y395567D01*
X1219482Y396034D01*
X1219348Y396500D01*
X1218948Y396900D01*
X1218348Y397100D01*
X1217682D01*
X1217282Y397234D01*
X1216948Y397567D01*
X1216815Y398034D01*
X1217015Y398500D01*
X1217482Y398834D01*
X1218015Y398967D01*
X1218548Y398834D01*
X1219015Y398500D01*
X1219215Y398034D01*
X1219082Y397567D01*
X1218748Y397234D01*
X1218348Y397100D01*
X1217682D01*
X1217082Y396900D01*
X1216682Y396500D01*
X1216548Y396034D01*
X1216682Y395567D01*
X1217015Y395234D01*
X1217548Y395034D01*
X1218015Y394967D01*
G01X1221482Y395434D02*
X1221948Y395100D01*
X1222482Y394967D01*
X1223015Y395100D01*
X1223482Y395500D01*
X1223815Y396100D01*
X1223948Y396700D01*
Y397434D01*
X1223815Y398034D01*
X1223482Y398567D01*
X1223082Y398834D01*
X1222615Y398967D01*
X1222082Y398834D01*
X1221682Y398567D01*
X1221415Y398167D01*
X1221282Y397634D01*
X1221415Y397167D01*
X1221748Y396700D01*
X1222148Y396434D01*
X1222615Y396367D01*
X1223148Y396500D01*
X1223548Y396834D01*
X1223948Y397434D01*
G01X1225815Y394967D02*
X1228615Y398967D01*
G01X1225815D02*
X1228615Y394967D01*
G01X1231815D02*
Y398967D01*
X1231015Y398167D01*
G01Y394967D02*
X1232615D01*
G01X1235148Y398300D02*
X1235548Y398700D01*
X1236015Y398900D01*
X1236548Y398967D01*
X1237215Y398834D01*
X1237682Y398500D01*
X1237815Y398100D01*
X1237748Y397700D01*
X1237482Y397367D01*
X1236148Y396700D01*
X1235548Y396234D01*
X1235148Y395567D01*
X1235015Y394967D01*
X1237815D01*
G01X1239748Y396634D02*
X1240215Y397100D01*
X1240615Y397367D01*
X1241148Y397500D01*
X1241615Y397367D01*
X1241948Y397100D01*
X1242215Y396700D01*
X1242282Y396234D01*
X1242215Y395834D01*
X1241948Y395434D01*
X1241548Y395100D01*
X1241082Y394967D01*
X1240548Y395100D01*
X1240082Y395500D01*
X1239815Y396100D01*
X1239748Y396767D01*
X1239882Y397634D01*
X1240082Y398100D01*
X1240415Y398567D01*
X1240882Y398900D01*
X1241348Y398967D01*
X1241815Y398834D01*
X1242148Y398500D01*
G54D31*
X1008268Y244094D03*
Y411417D03*
X1227166Y155511D03*
X1227165Y411417D03*
X1784450Y75450D03*
G54D22*
X332086Y408858D03*
X355708Y96456D03*
X450196Y257874D03*
X572243Y337992D03*
X1784450Y103550D03*
G54D13*
X8200Y857700D03*
X8000Y853500D03*
X8442Y847311D03*
X35304Y832220D03*
X34304Y897720D03*
X50395Y384679D03*
X40945Y384710D03*
X47483Y387776D03*
X43883Y387769D03*
X48820Y412435D03*
X39370Y412673D03*
X52000Y655500D03*
X40054Y823970D03*
X44804Y837220D03*
X36004Y839500D03*
X44500Y851500D03*
X49000Y861500D03*
X52000Y872720D03*
X37232Y877242D03*
X51896Y878668D03*
X42554Y891720D03*
X37211Y881115D03*
X37758Y884674D03*
X40304Y887220D03*
X51304Y882220D03*
X47804Y906720D03*
X43804Y907720D03*
X38804Y906220D03*
X41304Y927220D03*
X50270Y929186D03*
X41500Y941500D03*
X46500Y944500D03*
X59840Y384679D03*
X62783Y387776D03*
X66483Y387876D03*
X56883D03*
X53183Y387676D03*
X67715Y412518D03*
X58270Y412485D03*
X60304Y663220D03*
X55304Y669720D03*
X58804Y710220D03*
X64304Y698720D03*
X63304Y706720D03*
X68147Y722511D03*
X62704Y739620D03*
X64272Y736004D03*
X55304Y746220D03*
X65272Y758504D03*
X64683Y762056D03*
X59272Y790504D03*
X57772Y801504D03*
X61492Y803004D03*
X55022Y826720D03*
X66022Y827254D03*
X57304Y815720D03*
X61304Y815220D03*
X65804Y835720D03*
X57804Y834720D03*
X61804D03*
X55304Y849720D03*
X52304Y868220D03*
X60804Y907720D03*
X56804Y907220D03*
X52304Y906720D03*
X64804Y907720D03*
X52804Y943220D03*
X57770Y932686D03*
X55270Y929186D03*
X52770Y932686D03*
X62770D03*
X60270Y929186D03*
X52804Y938795D03*
X78740Y384915D03*
X69290Y384865D03*
X71883Y387976D03*
X76083D03*
X77165Y412590D03*
X76804Y662720D03*
Y710220D03*
X73804Y699720D03*
X81304Y710220D03*
X71846Y722426D03*
X77272Y724004D03*
X75432Y735059D03*
X83849Y735513D03*
X80272Y735103D03*
X68910Y760642D03*
X83112Y760720D03*
X75432Y758844D03*
X76272Y762504D03*
X80624Y764241D03*
X68762Y764239D03*
X77804Y773720D03*
X71804Y789720D03*
X82804Y794920D03*
X84804Y808720D03*
X73772Y822004D03*
X79000Y836500D03*
X69804Y835720D03*
X84221Y836078D03*
X77500Y832000D03*
X83838Y848133D03*
X76804Y847720D03*
X70909Y847325D03*
X72304Y869720D03*
X76304D03*
X81304Y884470D03*
X81804Y888720D03*
X72770Y906488D03*
X95304Y663720D03*
X89804Y669720D03*
X95304Y686220D03*
X97737Y698653D03*
X94804Y708220D03*
X99804Y709220D03*
X87772Y735059D03*
X92365Y735040D03*
X85672Y763504D03*
X96060Y762476D03*
X86404Y774720D03*
X85304Y768720D03*
X100804Y774720D03*
X93347Y765754D03*
X99804Y799720D03*
X85204Y798220D03*
X85804Y816220D03*
X92304Y835720D03*
X87804D03*
X87928Y848107D03*
X98304Y888220D03*
X95700Y926300D03*
X97804Y940720D03*
X112654Y314453D03*
X111304Y663720D03*
X111907Y698617D03*
X115804Y798720D03*
X105000Y834500D03*
X113222Y831222D03*
X112500Y835000D03*
X110500Y848500D03*
X115500D03*
X109054Y892720D03*
X102304Y895220D03*
X114054Y892720D03*
X106554Y895720D03*
X116554D03*
X111554Y896220D03*
X105804Y943220D03*
X109054Y932720D03*
X116600Y929924D03*
X114054Y932470D03*
X111554Y929720D03*
X101804Y940720D03*
X108804Y938795D03*
X115500Y983500D03*
X127654Y293453D03*
X132500Y312500D03*
X124500Y316000D03*
X132123Y318877D03*
X123654Y320953D03*
X131500Y324000D03*
X122906Y331953D03*
X122874Y354709D03*
X127301D03*
X131147D03*
X132500Y547000D03*
Y559600D03*
Y556000D03*
Y551500D03*
X133500Y582500D03*
X125050Y583000D03*
X126500Y587500D03*
X121685Y587919D03*
X134000Y587000D03*
X130000Y666500D03*
X129304Y798720D03*
X122500Y845500D03*
X128000Y870500D03*
X129100Y892924D03*
X124054Y892220D03*
X121600Y895266D03*
X119054Y892720D03*
X132804Y894220D03*
X126554Y895470D03*
X121598Y929924D03*
X131554Y929470D03*
X129054Y932720D03*
X126554Y929882D03*
X124098Y932515D03*
X119099Y932516D03*
X118000Y991500D03*
X145500Y283500D03*
X134874Y354709D03*
X147374D03*
X143147D03*
X139301D03*
X147500Y472100D03*
X135500Y511000D03*
X136000Y566000D03*
X136500Y576900D03*
Y573300D03*
Y580500D03*
Y569700D03*
X140500Y568000D03*
X144000Y572500D03*
X149100Y661100D03*
X143010Y676400D03*
X143500Y710500D03*
X141054Y795820D03*
X150225Y790412D03*
X146304Y804220D03*
X146500Y808220D03*
X162595Y296709D03*
X165793Y294309D03*
X153437Y320458D03*
X155874Y310209D03*
Y313961D03*
Y317807D03*
X152995Y329119D03*
X159674Y328609D03*
X159774Y320709D03*
X164147Y328699D03*
X155874Y326957D03*
Y323111D03*
X158874Y354709D03*
X155147D03*
X162801D03*
X166647D03*
X151301D03*
X160000Y465500D03*
X158500Y461500D03*
X153050Y486500D03*
X163225Y522080D03*
X154625Y550290D03*
X154755Y539310D03*
X163305Y554750D03*
X160500Y586500D03*
X156900D03*
X152948Y587000D03*
X166000Y662500D03*
X157750Y662250D03*
X166500Y650500D03*
X166875Y678285D03*
X162500Y670000D03*
X153500Y690275D03*
X163000Y710500D03*
X150900Y812500D03*
X154500D03*
X152500Y840000D03*
X157500Y867500D03*
X163000Y901000D03*
X158000D03*
X172285Y296964D03*
X181889Y297303D03*
X169639Y294309D03*
X179088Y294909D03*
X175242D03*
X183374Y328709D03*
X171874D03*
X171295Y320709D03*
X180315Y321209D03*
X167993Y328699D03*
X179622Y328749D03*
X175776D03*
X170374Y354709D03*
X182800Y465800D03*
Y471300D03*
X171500Y478699D03*
X177493Y533493D03*
X170339Y537396D03*
X180555Y560500D03*
X175993Y559938D03*
X175055Y569500D03*
X167469Y588969D03*
X172040Y688960D03*
X174000Y830500D03*
X170500Y835500D03*
X179500Y847000D03*
X172000Y868000D03*
X168400D03*
X183000Y865750D03*
X181000Y901000D03*
X174500Y901500D03*
X168500Y901000D03*
X197245Y296571D03*
X188295Y297209D03*
X193841Y297755D03*
X185039Y295209D03*
X191295D03*
X196063Y319209D03*
X186614Y319028D03*
X190295Y318709D03*
X192874Y326209D03*
X198864Y323297D03*
X192874Y334307D03*
Y330461D03*
X184295Y322209D03*
X192795Y321709D03*
X192874Y337907D03*
X189000Y347600D03*
X192874Y341611D03*
Y345457D03*
X192500Y431500D03*
X187300Y457300D03*
X191800D03*
X190800Y462800D03*
X189355Y526470D03*
X185000Y533562D03*
X185305Y521100D03*
X195725Y540750D03*
X195865Y552940D03*
X198500Y563000D03*
X189500Y573500D03*
X194500Y724000D03*
X198000Y785000D03*
X191875Y803125D03*
X186000Y841500D03*
X185000Y856000D03*
X185500Y848260D03*
X187000Y878000D03*
X199000Y891500D03*
X190500Y894000D03*
X195000Y891500D03*
X188000Y901000D03*
X197000D03*
Y897000D03*
X207086Y297418D03*
X204285Y294909D03*
X213733D03*
X200439D03*
X209887D03*
X205511Y320709D03*
X214960Y321044D03*
X208338Y323297D03*
X202710D03*
X212134D03*
X212500Y435000D03*
X204500Y470000D03*
X207773Y516562D03*
X208305Y548670D03*
Y536320D03*
Y562640D03*
X203000Y564500D03*
X201000Y625500D03*
X212500Y716500D03*
X204500Y721000D03*
X212500Y786000D03*
X204500Y817500D03*
X215250Y833750D03*
X205500Y830000D03*
X204000Y862000D03*
X212000Y891500D03*
X203500Y894000D03*
X208000Y892000D03*
X205500Y901000D03*
Y897000D03*
X217295Y296709D03*
X232500Y419000D03*
Y431000D03*
Y425000D03*
X229055Y497000D03*
X216500Y516000D03*
X228319Y524798D03*
X230000Y680500D03*
X221000Y723000D03*
X218000Y801500D03*
X223500Y825500D03*
X228000Y825000D03*
X232000D03*
X227000Y858000D03*
X217000Y858500D03*
X222000Y853500D03*
Y858500D03*
Y863500D03*
Y893600D03*
X231500Y898500D03*
X243755Y490890D03*
X242003Y506327D03*
X234755Y509700D03*
X245205Y504679D03*
X246613Y501365D03*
X237055Y513500D03*
X234185Y527138D03*
X248855Y532300D03*
X239555Y519500D03*
X240000Y829250D03*
X247500Y829500D03*
X237953Y861453D03*
X236500Y866000D03*
X259055Y500500D03*
X260288Y514589D03*
X264655Y511100D03*
X250055Y510800D03*
X256055Y531016D03*
X260555Y525500D03*
X253679Y523137D03*
X260605Y519245D03*
X263555Y534500D03*
X261255Y549000D03*
X265455Y544853D03*
X252055Y548760D03*
X257555Y549000D03*
X258500Y608500D03*
Y613500D03*
X253500Y608500D03*
X253555Y613500D03*
X251000Y835500D03*
X251500Y855500D03*
X261500Y857500D03*
X252000Y846500D03*
X252500Y851500D03*
X250362Y865000D03*
X253610Y863447D03*
X268300Y219800D03*
X279997Y514179D03*
X275555Y531500D03*
X275055Y521825D03*
X266055Y531725D03*
X272571Y541150D03*
X278367Y535140D03*
X269555Y536000D03*
X271451Y544616D03*
X278676Y539500D03*
X273000Y674000D03*
X270000Y870000D03*
Y865500D03*
X276500Y888500D03*
X269000Y921500D03*
X274000D03*
X280500Y955000D03*
X278050Y958500D03*
X273678Y958000D03*
X268178Y955500D03*
X296200Y94400D03*
X297929Y332000D03*
Y336000D03*
X293929Y342000D03*
X292525Y498780D03*
X292045Y504897D03*
X293273Y509500D03*
X282626Y516639D03*
X291530Y525407D03*
X283103Y520208D03*
X286588Y519305D03*
X292555Y533043D03*
X291755Y529000D03*
X286555Y524524D03*
X282555Y540700D03*
X283038Y536850D03*
X309500Y78500D03*
X313250Y85250D03*
X311500Y81500D03*
X314000Y102500D03*
X302000Y94300D03*
X299831Y144328D03*
X303677D03*
X305852Y163800D03*
X309698D03*
X305429Y219400D03*
Y223000D03*
X299395Y449160D03*
X303545Y445840D03*
X312925Y462560D03*
X300112Y483783D03*
X298662Y479783D03*
X305055Y472500D03*
X302555Y476000D03*
X312773Y529878D03*
X305255Y542600D03*
X313000Y582000D03*
X324500Y6000D03*
Y10500D03*
X316900Y65900D03*
X320500Y66000D03*
X327000Y89500D03*
X323000D03*
X319309Y89503D03*
X317500Y101000D03*
X317660Y96400D03*
X324200Y101900D03*
X330000Y118500D03*
X325929D03*
X321500D03*
X329929Y128500D03*
X325929Y127700D03*
X327100Y136294D03*
Y139857D03*
X326422Y152507D03*
Y148944D03*
X319800Y146898D03*
Y143052D03*
X322229Y218800D03*
X316129Y213000D03*
X329929Y241500D03*
X328000Y285000D03*
X327000Y308000D03*
X331000Y308018D03*
X330555Y467500D03*
X325873Y477006D03*
X325854Y480606D03*
X317195Y493280D03*
X317255Y514170D03*
X330491Y525490D03*
X315725Y549790D03*
X321555Y534500D03*
X329695Y534650D03*
X315135Y554980D03*
X317758Y581297D03*
X329055Y569500D03*
X321780Y575000D03*
X314930Y585500D03*
X321500Y688000D03*
X336700Y4300D03*
X341200D03*
X346000Y4400D03*
X333000Y90500D03*
X343000Y89000D03*
X339500Y75500D03*
X337500Y84250D03*
X342000Y102000D03*
X346000D03*
X334500Y118500D03*
X334600Y129468D03*
Y133031D03*
X345929Y183000D03*
X340679Y204900D03*
X332429Y210000D03*
X346404Y260000D03*
X344429Y312000D03*
X341500Y309500D03*
X343929Y320700D03*
X345929Y336500D03*
X341351Y336434D03*
X344929Y325500D03*
X342500Y340000D03*
X338500Y397500D03*
X343095Y446200D03*
X336375Y452870D03*
X338985Y467405D03*
X338595Y482590D03*
X339140Y512500D03*
X336445Y509330D03*
X343555Y517000D03*
X343688Y509533D03*
X334055Y526000D03*
X347213Y546700D03*
X340715Y545840D03*
X334555Y548500D03*
X341055Y534500D03*
X344655D03*
X345500Y556500D03*
X339888Y586388D03*
X346402Y653004D03*
X342500Y653000D03*
X335500Y868000D03*
X332129Y889371D03*
X331829Y885500D03*
X338000Y942000D03*
X339500Y936500D03*
Y960000D03*
X333500Y954000D03*
X355000Y4400D03*
X350500D03*
X360400D03*
X352000Y66000D03*
X357500Y79500D03*
Y75500D03*
X352500Y113000D03*
X348429Y130000D03*
X353929Y128500D03*
X351429Y126500D03*
X353300Y218400D03*
X351929Y332500D03*
X357055Y385000D03*
Y380500D03*
Y376500D03*
X355055Y394000D03*
Y389500D03*
X364015Y468450D03*
X349575Y479503D03*
X349815Y475550D03*
X364055Y512000D03*
X358797Y532258D03*
X354055Y534000D03*
X352095Y524040D03*
X362555Y534500D03*
X351815Y546880D03*
X348255Y534500D03*
X360500Y588500D03*
X350000Y652878D03*
X362210Y876200D03*
X364000Y869500D03*
X363480Y907783D03*
X362000Y904500D03*
X363000Y931500D03*
X359000D03*
X354000Y960000D03*
X363614Y971524D03*
X361000Y974000D03*
X360024Y979100D03*
X364900Y4400D03*
X369400D03*
X366600Y285800D03*
X377855Y300110D03*
X374000Y293500D03*
X372055Y319500D03*
X369555Y322500D03*
X371555Y347500D03*
X372055Y364000D03*
X375805Y380250D03*
X370275Y413540D03*
X371710Y406535D03*
X369555Y417500D03*
X370575Y409952D03*
X375055Y444500D03*
X367022Y482783D03*
X373555Y482500D03*
X378255Y471840D03*
X379000Y531000D03*
X367555Y545500D03*
X380000Y872000D03*
X371000Y866500D03*
X376041Y866041D03*
X375500Y906000D03*
Y901500D03*
X365500Y916000D03*
X369341Y916117D03*
X371100Y926000D03*
X377000Y927500D03*
X372300Y918749D03*
X371938Y922438D03*
X369500Y936500D03*
X368000Y932000D03*
X371000Y930000D03*
X376000Y960000D03*
X364396Y980109D03*
X366878Y977500D03*
X369200Y980252D03*
X372500Y977918D03*
X377464Y987493D03*
X377250Y982250D03*
X390000Y13500D03*
X385000D03*
X391000Y238500D03*
X388000Y233500D03*
X388149Y229780D03*
X393429Y229500D03*
X394929Y247000D03*
X395450Y265400D03*
X390100Y263600D03*
X387500Y261000D03*
X381500Y297000D03*
X395104Y291056D03*
X382455Y331870D03*
X386755Y447300D03*
X393055Y451000D03*
Y447400D03*
X385463Y450948D03*
X396055Y456500D03*
X386055Y454500D03*
X388885Y471100D03*
X381500Y534000D03*
X384046Y536546D03*
X389000Y604000D03*
X396000Y714500D03*
X392500Y718500D03*
X391000Y866500D03*
X395500Y867000D03*
X396500Y888500D03*
X396600Y895855D03*
X396330Y899705D03*
X396500Y904000D03*
X384000Y926500D03*
X389838Y942300D03*
X383500Y938500D03*
X388500Y955250D03*
X390000Y946500D03*
X397900Y231800D03*
X409929Y245400D03*
X399500Y240500D03*
X412513Y294800D03*
X398385Y292540D03*
X401855Y293500D03*
X408656Y291500D03*
X405555Y293500D03*
X401555Y318000D03*
X406555Y320500D03*
X403255Y425950D03*
X404500Y877300D03*
X410500Y885500D03*
X397600Y892000D03*
X399500Y901500D03*
X403250Y949000D03*
X408250Y949500D03*
X410500Y954500D03*
X405704Y952046D03*
X398250Y955000D03*
X400750Y952000D03*
X410000Y983500D03*
X410500Y987500D03*
X401500Y994500D03*
X414000Y8000D03*
X418192Y114237D03*
X421000Y231500D03*
X420429Y246400D03*
X424929Y264700D03*
X428100Y266500D03*
X419600Y282900D03*
X416500Y284800D03*
X422500Y271501D03*
X419455Y293000D03*
X416187Y294711D03*
X429500Y311000D03*
X425178Y798000D03*
X425278Y802000D03*
X418278Y828000D03*
Y840000D03*
X418500Y857500D03*
X418278Y854000D03*
Y846500D03*
X416046Y959546D03*
X414500Y948500D03*
X414215Y952089D03*
X422098Y948630D03*
X418500Y948500D03*
X413500Y957000D03*
X416000Y964000D03*
X420000D03*
X413600Y983500D03*
X425000Y994500D03*
X438500Y9000D03*
X433929Y100000D03*
X430540Y108750D03*
X439000Y254500D03*
X440500Y267000D03*
X433929Y264300D03*
X439800Y284100D03*
X444255Y283700D03*
X430900Y294550D03*
X439200D03*
X432500Y301000D03*
X435000Y294000D03*
X436416Y357676D03*
X432178Y798000D03*
X438178Y798500D03*
X444678Y798400D03*
X444778Y802100D03*
X438278D03*
X431778Y802000D03*
X442278Y846000D03*
X431500Y886000D03*
X437678D03*
X443178D03*
X431278Y883000D03*
X444278D03*
X437778D03*
X432000Y933500D03*
X430500Y962000D03*
X459429Y106000D03*
X448929Y99500D03*
X457500Y121000D03*
X450929Y118000D03*
X457429Y171500D03*
X462500Y169000D03*
X455054Y179475D03*
X458429Y175590D03*
X456000Y243500D03*
X460000D03*
X461100Y260050D03*
X459055Y263500D03*
X459500Y290100D03*
X458685Y425710D03*
X456178Y798000D03*
X452978Y805400D03*
X456278Y802100D03*
X455278Y846000D03*
X451278D03*
X459278D03*
X451178Y886000D03*
X460678D03*
X457578Y879700D03*
X450778Y883000D03*
X460778D03*
X471290Y118361D03*
X469000Y113000D03*
X472990Y113350D03*
X462700Y120800D03*
X471429Y133500D03*
X477291Y147500D03*
X477900Y153600D03*
X471000Y141000D03*
X477929Y158000D03*
X467600Y158400D03*
X465600Y162000D03*
X475216Y182917D03*
X470000Y188500D03*
X462679Y176900D03*
X466700Y259400D03*
X464055Y256500D03*
X469155Y297800D03*
X463371Y290371D03*
X474755Y308300D03*
X464200Y307838D03*
X463945Y349700D03*
X466655Y425340D03*
X472055Y425000D03*
X475678Y798500D03*
X463178D03*
X469178D03*
X475778Y802100D03*
X462778D03*
X469278D03*
X467278Y846000D03*
X468178Y886000D03*
X472178D03*
X473778Y883000D03*
X467278D03*
X488500Y114200D03*
X481929Y126500D03*
X481429Y150000D03*
X490100Y162100D03*
X491257Y315952D03*
X495103D03*
X487612Y318606D03*
X492555Y431250D03*
X482178Y886000D03*
X480278Y883000D03*
X488000Y904500D03*
X483500Y907500D03*
X503929Y127500D03*
X499390Y153500D03*
X503500D03*
X503929Y146500D03*
X506429Y149500D03*
X495929Y164500D03*
X499629Y178400D03*
X498855Y302851D03*
X508500Y320000D03*
X504453Y314200D03*
X500607D03*
X496155Y321700D03*
X495555Y369500D03*
X507355Y390800D03*
X505922Y415371D03*
X506163Y419973D03*
X508100Y605500D03*
X506000Y610000D03*
X497778Y843000D03*
Y838500D03*
Y847000D03*
X498500Y867500D03*
X513200Y121450D03*
X525679Y136250D03*
X517679Y125750D03*
X513000Y156500D03*
X512000Y320000D03*
X519706Y314000D03*
X515860D03*
X527002Y319359D03*
X523348D03*
X526500Y346532D03*
Y342969D03*
Y352969D03*
X520500Y351500D03*
Y347937D03*
Y358937D03*
X526500Y356532D03*
X520500Y362500D03*
X521500Y632500D03*
X533000Y153800D03*
X528500Y172000D03*
X539714Y179150D03*
X542500Y188500D03*
X537479Y197875D03*
X539073Y237300D03*
X531590Y297620D03*
X534500Y295500D03*
X528500Y310000D03*
X534629Y311171D03*
X534960Y321000D03*
X538614D03*
X529848Y325500D03*
X533502D03*
X550500Y188000D03*
X560500Y186000D03*
X555500Y194000D03*
X559500D03*
X545000Y195000D03*
X549926Y204000D03*
X557275Y214918D03*
X553675Y215913D03*
X550075D03*
X559961Y209419D03*
X546916Y217641D03*
X548000Y231000D03*
X547746Y225303D03*
X559971Y237753D03*
X553555Y321000D03*
X560253Y329500D03*
X557061Y334194D03*
X553155Y334300D03*
X548000Y369500D03*
X555935Y363000D03*
X559500Y604500D03*
X577000Y58000D03*
X572000Y189000D03*
X571398Y183602D03*
X561429Y174441D03*
X575500Y198400D03*
X576650Y204500D03*
X563100Y194000D03*
X568158Y206455D03*
X571461Y207887D03*
X569000Y217000D03*
X569127Y213100D03*
X564583Y206028D03*
X577119Y233139D03*
X564631Y234356D03*
X569322Y234220D03*
X573179Y233535D03*
X575425Y228505D03*
X574000Y269000D03*
X563704Y272000D03*
X563555Y333000D03*
X571555Y326000D03*
X562055Y347500D03*
X564215Y369339D03*
X566430Y366500D03*
X569555Y364000D03*
X562555Y364500D03*
X587175Y202525D03*
X591413Y199087D03*
X583500Y204500D03*
X585325Y198000D03*
X583325Y208500D03*
X583204Y236805D03*
X580709Y232091D03*
X619876Y195000D03*
X617828Y303250D03*
X613962D03*
X623500Y576500D03*
X622500Y608500D03*
X633578Y303250D03*
X629712D03*
X642800Y433587D03*
X641500Y449500D03*
X636500Y444800D03*
X640500Y444500D03*
X641625Y465375D03*
X635325Y457500D03*
X628250Y570200D03*
X628524Y591976D03*
X646500Y101000D03*
X650500D03*
X649323Y303250D03*
X645457D03*
X647125Y429375D03*
X652714Y428214D03*
X647500Y425500D03*
X645500Y459500D03*
X656162Y472338D03*
X654500Y494000D03*
X654300Y490300D03*
X647252Y576500D03*
X674469Y99380D03*
X674358Y103170D03*
X662248Y101000D03*
X667748Y104000D03*
X665073Y303250D03*
X661207D03*
X663500Y452000D03*
X672500D03*
X660000Y443500D03*
X669025Y441725D03*
X660500Y436538D03*
X663500Y456000D03*
Y460500D03*
X667500Y454000D03*
Y458500D03*
X672500Y456000D03*
Y460500D03*
X669462Y472500D03*
X667056Y475500D03*
X673010Y474436D03*
X673300Y579000D03*
X669000D03*
X663500Y610500D03*
X674688Y696751D03*
X670474Y808700D03*
X671500Y861000D03*
X673500Y864000D03*
X672000Y967750D03*
X667000Y969700D03*
X666750Y961550D03*
X685519Y55019D03*
X676748Y52000D03*
X684861Y58584D03*
X686000Y62000D03*
X684197Y74703D03*
X687055Y258500D03*
X683055D03*
X678055D03*
X681000Y452000D03*
X687500Y440500D03*
X681000Y456000D03*
Y460500D03*
X676500Y454000D03*
Y458500D03*
X690000Y460500D03*
X677500Y472500D03*
X688500Y606000D03*
X683000Y603950D03*
X677500Y612000D03*
X680000Y640000D03*
X691000Y704500D03*
X677500Y699000D03*
X682968Y758284D03*
X687968Y755284D03*
X677500Y773500D03*
X687968Y781784D03*
X678468Y805284D03*
X691300Y807300D03*
X679000Y865050D03*
X676500Y967750D03*
X706716Y82448D03*
X706055Y258500D03*
X705500Y575600D03*
X705900Y569200D03*
X698818Y759350D03*
X702918Y782734D03*
X703328Y800144D03*
X697250Y876750D03*
X704000Y892500D03*
X716034Y53966D03*
X716466Y65466D03*
X711216Y82402D03*
X720216Y82138D03*
X715716Y82652D03*
X713716Y121284D03*
X721716Y112784D03*
Y116784D03*
X717716Y121284D03*
X721716D03*
Y129284D03*
Y125284D03*
X711500Y179400D03*
X721200Y205800D03*
X710055Y258500D03*
X714055D03*
X725000Y452300D03*
X720700Y564200D03*
X717036Y563783D03*
X709750Y585200D03*
X719918Y754734D03*
X715118Y776134D03*
X723168Y774984D03*
X717468Y810784D03*
X722000Y808500D03*
X720500Y860000D03*
X712500Y859750D03*
X716250Y860250D03*
X710750Y863250D03*
X714000Y867500D03*
X714500Y891000D03*
X728966Y53966D03*
Y65466D03*
X740500Y75000D03*
X729716Y121284D03*
X725716D03*
X733498Y180750D03*
X733000Y193000D03*
X728100Y213800D03*
X732500Y455500D03*
X736000Y464500D03*
X728500Y482500D03*
X732500Y485500D03*
X734500Y547500D03*
X730000Y536500D03*
X734462Y553538D03*
X733500Y568500D03*
X729900D03*
X741500Y582450D03*
X737000Y583640D03*
X733268Y757984D03*
X740768Y763984D03*
X735500Y771984D03*
X735000Y780500D03*
X736000Y810500D03*
X733768Y800734D03*
X727468Y819284D03*
X733440Y875560D03*
X741050Y869500D03*
X740000Y886000D03*
X737290Y903000D03*
X733000Y969700D03*
X747800Y50200D03*
X754500Y67500D03*
X757200Y103100D03*
X745500Y145000D03*
X747000Y210000D03*
X755697Y303250D03*
X749750Y454000D03*
X755300Y489300D03*
X751484Y540600D03*
X746750Y571750D03*
X748000Y579500D03*
X755000Y727500D03*
X757500Y743500D03*
X745400Y877600D03*
X757000Y896400D03*
X749500Y974300D03*
X762250Y71000D03*
X761000Y88500D03*
Y82500D03*
X760600Y94500D03*
X770500Y136000D03*
X770900Y144300D03*
X765116Y187659D03*
X759563Y303250D03*
X771447D03*
X773500Y326000D03*
X758500Y457000D03*
X771000Y464000D03*
X772024Y478976D03*
X774500Y489500D03*
X760500D03*
X765009Y563491D03*
X766000Y635000D03*
X763000Y648000D03*
X767000Y648500D03*
X760125Y666875D03*
X771000Y689500D03*
X770646Y685354D03*
X760500Y707950D03*
X768000Y728000D03*
X763500Y839500D03*
X768000Y833000D03*
X766750Y849250D03*
X774500Y890500D03*
X775748Y188500D03*
X789500Y235837D03*
X787192Y303250D03*
X775313D03*
X788600Y449300D03*
X784800D03*
X784900Y453000D03*
X788800D03*
X779000Y458000D03*
X776000Y478828D03*
X788774Y482774D03*
X784274Y486274D03*
X790600Y547600D03*
X790000Y554500D03*
X786500Y575688D03*
X786032Y570468D03*
X783500Y649000D03*
X784804Y673304D03*
X785500Y666500D03*
X783746Y692754D03*
X779500Y705000D03*
X787500Y783500D03*
X782750Y845750D03*
X781000Y877000D03*
X785000Y892000D03*
X776750Y964750D03*
X785500Y969700D03*
X796000Y167600D03*
X795500Y163408D03*
X802942Y303250D03*
X791058D03*
X806808D03*
X798000Y400500D03*
X806274Y434726D03*
X796074Y479000D03*
X791000Y562000D03*
X802500Y579500D03*
X803500Y655000D03*
X798000Y706000D03*
X802000Y724000D03*
X794000Y723500D03*
X791500Y783500D03*
X801750Y867500D03*
X805250Y865750D03*
X794500Y897000D03*
X818000Y240900D03*
X821100Y348480D03*
Y352480D03*
X808500Y363500D03*
X811000Y430500D03*
X823500Y480000D03*
X814500Y472500D03*
X823500Y556500D03*
X815900Y564000D03*
X819500D03*
X810000Y735500D03*
X821250Y845750D03*
X810500Y851000D03*
X814000Y849500D03*
X819000Y868500D03*
X832000Y137500D03*
X826198Y239950D03*
X833555Y262000D03*
X838055Y262500D03*
X825500Y411100D03*
X832500Y404000D03*
X826500Y436000D03*
X826000Y465078D03*
X831000Y598500D03*
X833500Y613000D03*
X835000Y719000D03*
X826500Y743000D03*
X839250Y854500D03*
X826060Y863440D03*
X824560Y868560D03*
X856055Y262500D03*
X842555Y262000D03*
X847055Y262500D03*
X851555D03*
X854820Y352380D03*
X850540Y346070D03*
X844410Y346360D03*
X847500Y352000D03*
X852000Y401500D03*
X842000D03*
X847000Y396500D03*
Y401500D03*
Y406500D03*
X854000Y436500D03*
X849500Y622000D03*
X846250Y642250D03*
X854000Y640500D03*
X846500Y710000D03*
X852500Y710500D03*
X842500Y719500D03*
X845500Y865000D03*
X852600Y868500D03*
X873000Y68500D03*
X872000Y75500D03*
X870100Y237500D03*
X869544Y226000D03*
X860400Y231000D03*
X860555Y262500D03*
X865055D03*
X863820Y363880D03*
X868820D03*
X870500Y444000D03*
Y448000D03*
X871500Y484000D03*
X857500Y485500D03*
X862500Y621250D03*
X859500Y629500D03*
X872000Y636000D03*
X871000Y639500D03*
X870500Y665060D03*
X861250Y649250D03*
X867500Y655200D03*
X865500Y690500D03*
X860718Y683684D03*
X860500Y734000D03*
X877860Y316330D03*
X888750Y324660D03*
X884120Y351630D03*
X887950Y359730D03*
X874910Y360160D03*
X879510Y355410D03*
X887940Y380200D03*
X878000Y404500D03*
X877000Y409500D03*
X876000Y435500D03*
X886300Y443100D03*
X882700D03*
X885000Y438700D03*
X874450Y463500D03*
X877000Y479500D03*
X877500Y612500D03*
X876000Y631700D03*
X884200Y636500D03*
X878500Y695500D03*
X881000Y710000D03*
X899000Y312500D03*
X898000Y316000D03*
X903480Y324230D03*
X904600Y406600D03*
X893500Y427000D03*
X893600Y443100D03*
X889900D03*
X903075Y472000D03*
X918420Y449130D03*
X907000Y465050D03*
X917000Y752500D03*
X923000Y51500D03*
X936000Y373500D03*
X924465Y388465D03*
X934000Y448700D03*
X936030Y457540D03*
X937000Y489000D03*
X935400Y597300D03*
X939500Y352000D03*
X953500Y348927D03*
X944000Y434000D03*
X958500Y187500D03*
X957990Y191064D03*
X962000Y251500D03*
X965500Y260500D03*
X963500Y256000D03*
X959500Y351688D03*
X965000Y364500D03*
X964000Y354000D03*
X968085Y452065D03*
X970382Y455872D03*
X961700Y477500D03*
X957500Y585500D03*
X961500D03*
X970750Y703000D03*
X980078Y204578D03*
X980960Y195257D03*
X980490Y198827D03*
X982075Y439500D03*
X973015Y453416D03*
X977000Y547500D03*
X982500Y549500D03*
X978000Y554000D03*
X975000Y701000D03*
X989000Y66500D03*
X1003000Y59500D03*
X996500Y167000D03*
X988660Y190500D03*
X988900Y434800D03*
X992690Y466750D03*
X996910Y466560D03*
X998000Y461500D03*
X994500Y491000D03*
X1003422Y490578D03*
X992000Y505500D03*
X1002500Y520000D03*
X990500Y536500D03*
X994500Y543800D03*
X998500Y591500D03*
X989000Y659500D03*
Y757150D03*
X1001000Y771500D03*
X1012000Y43000D03*
X1016500Y87500D03*
X1020500Y124500D03*
Y142000D03*
X1017274Y219274D03*
X1014000Y487000D03*
X1007500Y487500D03*
Y507000D03*
X1008500Y533400D03*
X1016500Y519500D03*
X1008500Y543700D03*
X1013500Y559000D03*
X1016900Y561000D03*
X1017982Y585018D03*
X1007032Y879968D03*
X1011966Y893534D03*
X1007532Y902468D03*
X1020282Y911218D03*
X1033500Y118000D03*
X1025500Y129500D03*
X1033500Y124000D03*
X1037085Y137000D03*
X1023000Y155000D03*
X1034000D03*
X1028000Y164500D03*
X1023600Y173000D03*
X1036019Y203177D03*
X1036000Y199500D03*
X1035922Y209578D03*
X1031524Y218476D03*
X1033900Y225500D03*
X1027426Y346500D03*
X1023000Y347000D03*
X1031000Y348500D03*
Y355950D03*
X1030000Y403500D03*
X1036500Y581500D03*
X1035000Y594500D03*
X1021000Y588500D03*
X1025500Y657000D03*
X1023500Y727000D03*
X1037000Y734000D03*
X1024387Y738230D03*
X1035000Y800000D03*
Y804500D03*
X1021468Y866968D03*
X1032600Y867657D03*
X1031500Y884500D03*
X1035216Y884468D03*
X1035000Y888500D03*
Y880500D03*
X1032657Y901500D03*
X1027716Y914784D03*
X1032200Y921500D03*
X1045031Y138031D03*
X1041485Y137409D03*
X1039468Y155284D03*
X1048968D03*
X1053500Y153000D03*
X1044000D03*
X1048968Y150784D03*
X1039500Y151000D03*
X1048968Y159284D03*
X1039500Y159500D03*
X1053500Y157500D03*
X1044000D03*
X1040000Y182000D03*
X1052500Y187500D03*
X1045968Y185500D03*
X1037500Y225500D03*
X1040000Y579000D03*
X1038000Y604000D03*
X1053500Y620500D03*
X1046000Y644000D03*
X1038000Y635000D03*
X1042450Y648500D03*
X1045500Y639500D03*
X1050092Y655052D03*
X1042400Y684500D03*
X1052500Y693000D03*
X1052678Y704084D03*
X1038500Y706500D03*
X1052500Y709000D03*
Y700000D03*
X1041410Y708804D03*
Y704224D03*
X1052648Y712724D03*
X1040208Y745020D03*
X1052500Y773350D03*
X1044000Y763940D03*
X1039000Y884500D03*
X1042500Y930000D03*
X1064000Y80000D03*
X1055500D03*
X1059500D03*
X1068000D03*
Y76000D03*
X1064000D03*
X1059500D03*
X1055500D03*
X1068500Y118500D03*
X1069000Y124500D03*
X1057968Y155284D03*
X1058000Y150500D03*
Y159500D03*
X1060900Y173534D03*
X1060509Y177126D03*
X1066500Y185500D03*
X1056500Y194000D03*
X1060000Y207500D03*
X1061000Y211500D03*
X1055000Y219284D03*
X1060766Y395426D03*
X1061200Y399000D03*
X1068300Y488700D03*
X1059000Y558190D03*
X1058000Y599500D03*
X1056000Y604000D03*
X1058500Y660900D03*
X1054900D03*
X1070000Y650725D03*
X1058350Y681450D03*
X1068500Y677000D03*
X1054500Y697000D03*
X1068500Y687000D03*
X1066000Y717000D03*
X1059800Y719740D03*
X1054000Y735000D03*
X1056350Y748000D03*
X1063000Y780000D03*
X1071000Y71000D03*
X1077250Y102000D03*
X1077500Y97000D03*
Y107500D03*
X1072000Y136000D03*
X1086000Y126500D03*
X1074500Y185500D03*
X1080300Y191000D03*
X1084500Y202500D03*
X1072500Y208924D03*
X1078500Y464000D03*
X1080000Y520000D03*
X1081000Y548000D03*
Y544400D03*
X1084599Y544520D03*
X1086000Y556000D03*
X1071500Y589000D03*
X1074500Y627500D03*
X1073000Y637500D03*
X1085000Y661000D03*
X1074000Y677000D03*
X1073500Y672000D03*
X1074000Y683000D03*
X1074500Y694754D03*
X1074426Y687255D03*
X1074389Y691155D03*
X1074000Y699500D03*
X1074148Y711624D03*
X1074600Y707724D03*
X1074000Y703500D03*
X1073384Y722384D03*
X1073000Y730834D03*
Y726444D03*
X1074288Y715534D03*
X1084300Y741874D03*
X1077500Y745374D03*
X1072000Y743500D03*
X1071500Y739000D03*
X1077500Y759000D03*
X1084000Y748099D03*
X1070098Y764500D03*
X1083700Y835725D03*
X1085468Y895968D03*
X1077000Y943075D03*
X1083200Y956500D03*
X1088000Y85500D03*
X1098000Y126500D03*
X1093894D03*
X1090028D03*
X1092500Y461500D03*
X1098500Y465000D03*
X1089000Y508500D03*
X1100575Y559075D03*
X1098000Y562000D03*
X1091425Y551425D03*
X1093500Y640000D03*
X1094500Y657500D03*
X1091000Y692519D03*
X1090257Y724253D03*
X1087600Y727029D03*
X1094853Y726853D03*
X1098000Y775000D03*
X1093000Y791000D03*
X1097500Y784500D03*
X1095500Y812000D03*
X1098500Y823344D03*
X1097500Y849000D03*
X1092718Y859984D03*
X1089000Y867284D03*
X1099623Y869123D03*
X1093468Y896968D03*
X1097423Y906546D03*
X1093500Y905500D03*
X1110318Y275600D03*
X1111500Y517500D03*
X1107500Y580000D03*
X1114883Y591925D03*
X1106000Y609500D03*
Y605500D03*
X1111500Y718500D03*
X1107000Y763000D03*
Y757500D03*
X1110300Y790000D03*
X1111834Y813334D03*
X1113500Y824500D03*
X1111000Y836000D03*
X1107160Y843160D03*
X1118034Y847034D03*
X1113768D03*
X1116468Y870284D03*
Y874284D03*
Y865784D03*
X1112468Y870284D03*
X1114500Y886000D03*
X1103000Y888300D03*
X1118500Y886000D03*
X1123000Y250500D03*
X1120600Y282300D03*
X1128000Y288500D03*
X1132300Y288800D03*
X1130000Y361500D03*
X1124327Y465391D03*
X1123500Y521500D03*
X1128149Y525261D03*
X1130928Y527550D03*
X1132000Y562000D03*
X1125600Y570600D03*
X1135000Y597000D03*
X1132222Y593278D03*
X1119487Y588088D03*
X1122353Y590268D03*
X1125000Y603050D03*
X1134000Y613500D03*
X1126000Y618000D03*
Y627329D03*
X1131000Y631000D03*
X1121500Y621600D03*
X1130490Y627436D03*
X1125041Y631000D03*
X1120500Y729500D03*
X1124000Y729000D03*
X1128430Y749640D03*
X1132960Y752950D03*
X1126210Y752810D03*
X1126642Y785505D03*
X1123200Y783900D03*
X1130030Y820000D03*
X1121000Y823500D03*
X1135468Y854032D03*
X1120468Y870284D03*
X1131275Y867725D03*
X1146500Y267000D03*
X1146000Y258500D03*
X1151000Y264500D03*
X1146500Y275500D03*
X1145800Y282284D03*
X1136100Y288900D03*
X1136450Y294650D03*
X1150640Y359860D03*
X1146640D03*
X1142640D03*
X1151500Y449000D03*
Y522000D03*
X1143500Y542000D03*
X1147500D03*
X1136075Y559075D03*
X1145900Y579800D03*
X1136500Y592500D03*
X1139632Y594441D03*
X1140500Y589000D03*
X1141100Y585400D03*
X1147000Y619000D03*
X1147400Y729900D03*
X1166000Y232000D03*
X1162468Y257968D03*
X1153700Y267700D03*
X1168000Y302500D03*
X1166000Y290000D03*
X1156100Y316405D03*
X1168076Y310046D03*
X1152500Y311000D03*
X1158000Y309500D03*
X1152500Y318500D03*
X1160000D03*
X1156100Y312795D03*
X1165000Y308175D03*
Y304565D03*
X1167000Y321000D03*
Y326450D03*
X1161530Y360430D03*
X1157480Y361620D03*
X1157700Y368500D03*
X1160058Y364558D03*
X1155400Y371500D03*
X1164000Y397000D03*
X1168000Y390250D03*
X1166500Y415500D03*
X1155500Y450758D03*
Y446892D03*
X1161000Y541500D03*
X1154000Y589000D03*
X1155000Y594500D03*
X1165476Y613393D03*
X1152500Y608500D03*
X1165672Y609672D03*
X1164500Y628723D03*
X1159075Y630600D03*
X1154847Y630908D03*
X1156377Y627623D03*
X1160333Y753600D03*
X1153500Y784190D03*
X1164500Y857500D03*
X1162000Y960625D03*
X1171000Y232000D03*
X1181427Y251500D03*
X1180677Y256500D03*
X1173777Y290125D03*
X1169777D03*
X1177500Y290000D03*
X1174752Y320504D03*
X1173125Y323716D03*
X1169515D03*
X1175000Y327000D03*
X1184000Y351500D03*
X1174500Y366000D03*
X1182000Y357000D03*
X1174400Y356500D03*
X1178000D03*
X1175125Y370000D03*
X1176500Y383500D03*
X1174500Y404000D03*
X1182500Y407000D03*
X1173500Y422500D03*
Y554000D03*
X1179934Y567000D03*
X1181350Y595450D03*
X1169075Y613500D03*
X1183000Y628000D03*
X1177100Y624750D03*
X1178500Y653100D03*
X1184500Y749500D03*
Y772782D03*
X1173200Y789500D03*
X1184750Y781000D03*
X1177000Y860000D03*
X1169000Y856000D03*
X1181500Y949000D03*
X1186500Y232000D03*
X1188000Y248500D03*
X1196334Y290561D03*
X1185283Y290513D03*
X1192743Y289800D03*
X1188877D03*
X1199685Y344588D03*
X1196075D03*
X1198000Y348000D03*
X1192000Y344500D03*
X1197000Y372500D03*
X1187500Y411000D03*
X1197000Y409500D03*
X1189000Y421500D03*
X1195000Y428000D03*
X1197675Y533125D03*
X1191000Y528000D03*
X1189000Y533825D03*
X1194564Y530936D03*
X1185500Y548075D03*
X1200500Y547925D03*
X1186000Y615500D03*
X1196000Y605800D03*
X1184956Y619272D03*
X1191000Y663000D03*
X1193804Y657175D03*
X1191000Y667000D03*
X1197500Y665500D03*
X1199551Y683968D03*
X1195937Y683849D03*
X1189890Y684053D03*
X1192937Y683911D03*
X1196500Y745500D03*
Y736687D03*
X1192500Y745500D03*
X1192038Y761481D03*
X1188000Y762500D03*
X1188500Y773000D03*
X1184975Y767500D03*
X1194000Y764500D03*
X1190000Y767500D03*
X1198718Y800782D03*
X1196000Y847500D03*
X1188875Y856625D03*
X1196000Y874500D03*
X1208500Y202000D03*
X1209000Y212500D03*
X1208000Y231000D03*
X1207500Y239500D03*
X1201922Y248500D03*
X1202177Y260000D03*
X1208500Y283500D03*
X1208000Y271499D03*
Y297638D03*
Y309000D03*
X1206500Y330000D03*
X1208500Y321500D03*
X1203500Y345000D03*
X1208500Y346400D03*
Y359000D03*
X1210800Y379700D03*
X1208000Y371000D03*
X1216000Y390000D03*
X1209500Y404500D03*
X1216500Y439500D03*
X1212500Y436000D03*
X1209000Y438500D03*
X1217000Y452500D03*
X1210000Y507500D03*
X1209500Y514000D03*
X1213100D03*
X1214450Y509000D03*
X1206400Y536800D03*
X1210000D03*
X1201500Y535000D03*
X1209500Y561910D03*
X1205240Y568760D03*
X1215500Y605300D03*
X1207700Y605500D03*
X1208500Y623000D03*
X1204500Y659500D03*
X1203181Y683968D03*
X1206781Y684003D03*
X1213598Y699164D03*
X1216000Y702500D03*
X1210500Y733500D03*
X1206500Y757000D03*
X1213500Y756000D03*
X1201968Y757500D03*
X1212840Y781000D03*
X1202218Y811282D03*
X1211000Y847500D03*
X1204000Y862000D03*
X1217250Y862250D03*
X1208940Y874560D03*
X1211500Y882500D03*
X1227500Y500500D03*
Y504246D03*
X1220500Y513000D03*
X1229500Y533000D03*
X1231632Y537000D03*
X1221500Y539500D03*
X1233000Y554502D03*
X1219200Y564600D03*
X1221500Y633000D03*
X1231450Y677500D03*
X1225500Y714500D03*
X1229000Y716000D03*
Y726500D03*
Y719600D03*
Y740000D03*
X1230219Y747469D03*
X1232000Y738000D03*
X1234000Y747500D03*
X1224500Y757500D03*
X1228547Y772547D03*
Y778453D03*
X1231000Y768500D03*
X1221000Y764750D03*
X1233000Y782500D03*
X1223500Y798500D03*
X1223000Y826500D03*
X1230500Y841000D03*
X1218500Y834500D03*
X1229807Y847000D03*
X1239000Y190500D03*
X1239500Y204000D03*
X1240000Y209449D03*
X1239500Y214000D03*
X1239000Y251500D03*
X1241777Y265700D03*
X1241377Y274900D03*
X1238500Y290000D03*
X1239000Y302437D03*
X1238500Y316500D03*
X1250158Y326463D03*
X1238500Y325985D03*
X1239000Y338900D03*
Y352800D03*
X1239500Y366000D03*
X1234177Y379500D03*
X1243000Y431500D03*
X1250000Y422000D03*
X1234500Y439000D03*
X1248250Y439250D03*
X1243000Y446650D03*
X1250450Y462000D03*
X1242000Y459000D03*
X1247800Y472750D03*
X1246750Y476250D03*
X1249000Y509500D03*
X1249251Y528688D03*
X1235482Y546982D03*
X1240000Y546500D03*
Y542900D03*
X1240173Y550327D03*
X1250500Y567000D03*
X1241000Y631500D03*
X1237500Y675500D03*
X1239500Y671000D03*
X1235000Y682000D03*
X1244371Y733129D03*
X1236500Y737925D03*
X1243000Y743000D03*
X1241000Y734500D03*
X1240016Y761500D03*
X1238000Y764500D03*
X1249500Y765500D03*
X1248950Y769500D03*
X1248500Y775500D03*
X1248950Y782450D03*
X1238047Y791953D03*
X1240045Y788957D03*
X1241984Y796000D03*
X1243953Y789000D03*
X1240660Y829000D03*
X1245650Y821850D03*
X1235258Y820758D03*
X1257000Y33000D03*
X1256500Y166500D03*
X1261000D03*
X1265000Y169000D03*
Y174000D03*
X1258000Y205000D03*
X1265000Y211500D03*
X1261000Y207500D03*
Y211500D03*
X1260677Y237000D03*
X1264177Y233500D03*
X1256000Y252000D03*
X1262558Y254942D03*
X1261677Y241500D03*
Y245500D03*
X1251500Y266500D03*
X1264500Y260000D03*
X1254944Y268567D03*
X1263000Y278500D03*
X1250677Y287500D03*
Y283500D03*
X1251700Y274000D03*
X1254203Y282770D03*
X1254944Y272433D03*
X1260577Y299968D03*
Y296102D03*
X1261000Y292500D03*
X1261006Y303543D03*
X1252564Y290566D03*
X1253477Y312800D03*
X1253577Y308800D03*
X1253500Y316500D03*
Y305000D03*
X1257000Y311000D03*
X1253177Y320500D03*
Y324500D03*
X1265000Y426500D03*
X1259968Y444284D03*
X1260000Y448500D03*
X1264500Y446500D03*
X1260000Y440000D03*
X1264500Y442000D03*
X1257468Y478500D03*
X1253000Y511000D03*
X1251500Y531500D03*
X1260500Y546400D03*
X1263500Y550000D03*
X1258000Y555400D03*
X1255000Y609300D03*
X1266500Y617500D03*
X1265000Y647500D03*
X1257500Y635500D03*
X1265000Y661000D03*
Y657000D03*
X1265500Y652500D03*
X1257100Y664300D03*
X1263121Y678621D03*
X1259000Y678950D03*
X1262300Y670700D03*
X1266000Y665600D03*
X1262500Y699825D03*
X1253500Y778465D03*
X1257950Y809250D03*
X1264000Y853000D03*
X1279500Y150500D03*
X1276500Y234000D03*
X1267677Y232500D03*
X1280500Y338000D03*
Y404550D03*
X1280000Y420500D03*
X1278500Y448500D03*
Y444000D03*
X1274000Y447000D03*
X1269468Y444284D03*
Y448284D03*
X1278500Y439500D03*
X1269468Y439784D03*
X1274000Y442000D03*
X1272500Y466600D03*
X1270000Y477000D03*
X1271000Y573500D03*
Y568500D03*
X1282500Y598000D03*
X1274500Y606000D03*
X1278500Y603500D03*
X1271000Y617500D03*
X1279340Y618660D03*
X1282500Y645000D03*
X1272451Y642500D03*
X1272502Y638900D03*
X1281268Y661780D03*
X1268805Y655405D03*
X1282300Y678000D03*
X1282500Y669561D03*
X1273702Y667662D03*
X1275885Y670525D03*
X1267500Y675000D03*
Y684878D03*
X1281500Y713000D03*
X1279000Y746575D03*
X1267500Y779000D03*
Y783000D03*
X1269500Y835000D03*
X1290874Y34376D03*
X1299500Y236000D03*
X1295500Y291500D03*
X1292500Y402000D03*
X1289000Y415500D03*
X1285700Y529700D03*
X1293960Y528740D03*
X1294600Y524200D03*
X1291300Y540900D03*
X1297500Y562000D03*
X1286500Y569000D03*
X1294000Y587500D03*
X1288335Y594048D03*
X1287482Y590500D03*
X1293500Y593000D03*
X1285557Y585000D03*
X1289570Y597430D03*
X1284825Y621500D03*
X1294000Y628000D03*
X1299000Y641500D03*
X1296000Y638500D03*
X1290500Y635500D03*
X1286500Y652500D03*
X1297500Y665000D03*
X1291500Y666000D03*
X1289500Y669000D03*
X1284490Y710936D03*
X1296500Y830782D03*
X1298034Y907034D03*
X1306000Y43000D03*
X1309500Y51000D03*
X1304050Y296500D03*
X1307500Y320500D03*
X1308000Y311000D03*
X1312750Y314000D03*
X1306000Y329000D03*
Y334500D03*
Y338500D03*
X1311000Y435000D03*
Y463500D03*
X1302000Y475000D03*
X1304700Y536000D03*
X1302500Y559500D03*
X1307000Y573412D03*
X1307900Y577412D03*
X1306817Y592412D03*
X1306617Y587512D03*
X1308817Y595412D03*
X1310500Y625000D03*
X1312000Y645784D03*
X1311000Y651900D03*
X1310425Y660062D03*
X1311100Y656400D03*
X1304400Y661400D03*
X1311700Y681500D03*
X1312115Y672000D03*
X1311000Y677284D03*
X1311300Y687500D03*
X1313500Y710000D03*
X1305000Y739750D03*
X1308100Y748200D03*
X1306000Y782500D03*
X1314284D03*
X1304500Y838000D03*
X1300784Y838716D03*
X1312500Y838000D03*
X1305000Y850500D03*
X1303750Y862250D03*
X1312000Y850500D03*
X1307468Y884532D03*
X1314500Y921500D03*
X1331000Y120000D03*
X1322500Y299000D03*
X1324000Y290500D03*
X1322000Y318500D03*
X1322500Y337000D03*
X1317000Y336000D03*
X1330500Y441000D03*
X1332000Y459250D03*
X1323500Y452500D03*
X1326617Y594412D03*
X1325950Y599000D03*
X1329317Y626512D03*
X1323117Y626412D03*
X1328000Y649000D03*
X1328968Y679684D03*
X1329468Y666468D03*
X1323500Y702000D03*
X1322000Y705500D03*
X1318784Y793716D03*
X1325250Y834250D03*
X1316500Y839000D03*
X1317000Y850500D03*
X1318113Y846371D03*
X1321466Y907034D03*
X1339000Y54000D03*
X1347000Y48000D03*
X1342500Y51000D03*
X1333100Y58600D03*
X1347000Y88000D03*
X1347500Y116000D03*
X1343500Y112000D03*
X1336500Y270874D03*
X1339000Y274000D03*
X1339500Y305500D03*
X1341873Y344873D03*
X1344000Y434500D03*
X1340200D03*
X1335000Y443250D03*
X1340200Y438300D03*
X1343900Y438500D03*
X1343000Y466500D03*
X1334500Y557000D03*
X1335317Y575412D03*
X1344617Y588712D03*
Y593412D03*
X1342648Y612412D03*
X1347617Y610412D03*
X1346617Y626912D03*
X1342367Y627662D03*
X1334500Y636000D03*
X1333468Y680000D03*
X1334500Y669000D03*
X1352000Y85500D03*
X1349500Y112000D03*
X1350000Y276500D03*
X1354500Y276000D03*
X1350084Y296500D03*
X1358500Y288916D03*
X1353000Y390000D03*
Y402000D03*
X1362500Y459000D03*
X1353500Y466500D03*
X1351000Y455750D03*
X1355500Y556500D03*
X1360817Y557812D03*
X1356817Y579012D03*
X1364617Y592912D03*
X1349317Y593412D03*
X1360200Y614800D03*
X1353117Y610412D03*
X1353517Y627512D03*
X1363100Y627000D03*
X1349817Y628612D03*
X1357300Y617700D03*
X1369720Y106365D03*
X1379500Y274500D03*
X1381500Y292000D03*
X1376000D03*
X1379500Y314000D03*
X1375500Y328000D03*
X1370500Y356500D03*
X1368000Y450500D03*
X1374500Y462800D03*
X1369617Y557012D03*
X1367617Y570012D03*
X1390004Y106000D03*
Y122600D03*
X1384500Y274500D03*
Y331500D03*
X1784450Y834150D03*
G54D14*
X15000Y1008622D03*
X90119Y72219D03*
X227041Y1008622D03*
X653974Y1008621D03*
X955315Y850829D03*
X1157095Y128841D03*
X1385000Y1008622D03*
X1387875Y-15015D03*
X1784450Y215950D03*
G54D32*
X1045000Y32598D03*
X1096732D03*
X1784450Y468850D03*
G54D23*
X402953Y23622D03*
X413189D03*
X423425D03*
X1784450Y749850D03*
G54D33*
X1066929Y43267D03*
X1057086D03*
X1084646D03*
X1074803D03*
X1784450Y637450D03*
G54D24*
X537994Y303150D03*
X825984D03*
X1784450Y187850D03*
G54D15*
X35435Y373228D03*
X82675D03*
X1784450Y272150D03*
G54D25*
X545079Y290355D03*
Y315945D03*
X560829Y290355D03*
X556889Y298230D03*
X552954Y290355D03*
X549014Y298230D03*
X560829Y315945D03*
X556889Y308070D03*
X552954Y315945D03*
X549014Y308070D03*
X576574Y290355D03*
X572639Y298230D03*
X568699Y290355D03*
X564764Y298230D03*
X576574Y315945D03*
X572639Y308070D03*
X568699Y315945D03*
X564764Y308070D03*
X592324Y290355D03*
X588384Y298230D03*
X584449Y290355D03*
X580514Y298230D03*
X592324Y315945D03*
X588384Y308070D03*
X584449Y315945D03*
X580514Y308070D03*
X608069Y290355D03*
X604134Y298230D03*
X600199Y290355D03*
X596259Y298230D03*
X608069Y315945D03*
X604134Y308070D03*
X600199Y315945D03*
X596259Y308070D03*
X627754Y298230D03*
X623819Y290355D03*
X619884Y298230D03*
X615944Y290355D03*
X612009Y298230D03*
X627754Y308070D03*
X623819Y315945D03*
X619884Y308070D03*
X615944Y315945D03*
X612009Y308070D03*
X643504Y298230D03*
X639569Y290355D03*
X635629Y298230D03*
X631694Y290355D03*
X643504Y308070D03*
X639569Y315945D03*
X635629Y308070D03*
X631694Y315945D03*
X659254Y298230D03*
X655314Y290355D03*
X651379Y298230D03*
X647439Y290355D03*
X659254Y308070D03*
X655314Y315945D03*
X651379Y308070D03*
X647439Y315945D03*
X674999Y298230D03*
X671064Y290355D03*
X667124Y298230D03*
X663189Y290355D03*
X674999Y308070D03*
X671064Y315945D03*
X667124Y308070D03*
X663189Y315945D03*
X690749Y298230D03*
X686809Y290355D03*
X682874Y298230D03*
X678939Y290355D03*
X690749Y308070D03*
X686809Y315945D03*
X682874Y308070D03*
X678939Y315945D03*
X706494Y298230D03*
X702559Y290355D03*
X698624Y298230D03*
X694684Y290355D03*
X706494Y308070D03*
X702559Y315945D03*
X698624Y308070D03*
X694684Y315945D03*
X726179Y290355D03*
X722244Y298230D03*
X718309Y290355D03*
X714369Y298230D03*
X710434Y290355D03*
X726179Y315945D03*
X722244Y308070D03*
X718309Y315945D03*
X714369Y308070D03*
X710434Y315945D03*
X741929Y290355D03*
X737994Y298230D03*
X734054Y290355D03*
X730119Y298230D03*
X741929Y315945D03*
X737994Y308070D03*
X734054Y315945D03*
X730119Y308070D03*
X757679Y290355D03*
X753739Y298230D03*
X749804Y290355D03*
X745864Y298230D03*
X757679Y315945D03*
X753739Y308070D03*
X749804Y315945D03*
X745864Y308070D03*
X773424Y290355D03*
X769489Y298230D03*
X765549Y290355D03*
X761614Y298230D03*
X773424Y315945D03*
X769489Y308070D03*
X765549Y315945D03*
X761614Y308070D03*
X789174Y290355D03*
X785234Y298230D03*
X781299Y290355D03*
X777364Y298230D03*
X789174Y315945D03*
X785234Y308070D03*
X781299Y315945D03*
X777364Y308070D03*
X804919Y290355D03*
X800984Y298230D03*
X797049Y290355D03*
X793109Y298230D03*
X804919Y315945D03*
X800984Y308070D03*
X797049Y315945D03*
X793109Y308070D03*
X820669Y290355D03*
X816734Y298230D03*
X812794Y290355D03*
X808859Y298230D03*
X820669Y315945D03*
X816734Y308070D03*
X812794Y315945D03*
X808859Y308070D03*
X840354Y298230D03*
X836419Y290355D03*
X832479Y298230D03*
X840354Y308070D03*
X836419Y315945D03*
X832479Y308070D03*
X856104Y298230D03*
X852164Y290355D03*
X848229Y298230D03*
X844289Y290355D03*
X856104Y308070D03*
X852164Y315945D03*
X848229Y308070D03*
X844289Y315945D03*
X871849Y298230D03*
X867914Y290355D03*
X863974Y298230D03*
X860039Y290355D03*
X871849Y308070D03*
X867914Y315945D03*
X863974Y308070D03*
X860039Y315945D03*
X1784450Y777950D03*
G54D34*
X1224016Y180709D03*
X1784450Y300250D03*
G54D16*
X50000Y659500D03*
X58804Y699720D03*
X109000Y844220D03*
X111000Y981500D03*
X112900Y988500D03*
X124500Y515500D03*
X128000Y544050D03*
X121200Y584278D03*
X166200Y506500D03*
X172000Y486400D03*
X182000Y577500D03*
X176938Y680465D03*
X182500Y677500D03*
X242500Y565500D03*
X234000Y562000D03*
X236500Y574000D03*
X238500Y705000D03*
X253500Y707250D03*
X294500Y98500D03*
X299300Y84200D03*
X311500Y153000D03*
X299000Y148000D03*
X307129Y143000D03*
X305029Y147700D03*
X313402Y156000D03*
X304300Y160200D03*
X304100Y167000D03*
X311300D03*
X312500Y159100D03*
X307500Y299000D03*
X306155Y497700D03*
X305155Y504900D03*
X330250Y80000D03*
X330900Y134500D03*
X319014Y152977D03*
X328700Y154400D03*
X328629Y146800D03*
X330400Y141600D03*
X331040Y152601D03*
X330929Y148600D03*
X317248Y156000D03*
X318200Y159100D03*
X326000Y292500D03*
X320238Y497183D03*
X320338Y507683D03*
X316273Y520282D03*
X347000Y120040D03*
X340000D03*
X338000Y127500D03*
X337400Y134500D03*
X334000Y147600D03*
X344055Y529000D03*
X340055Y524000D03*
X342971Y525750D03*
X339000Y878500D03*
X336000Y871500D03*
X339000Y894000D03*
Y885500D03*
X337300Y949500D03*
X357394Y131496D03*
X353740Y133300D03*
X362009Y142520D03*
Y148819D03*
Y155119D03*
X352040Y143000D03*
X349829Y153400D03*
X362036Y170876D03*
X362034Y161406D03*
X355084Y172441D03*
X351929Y162200D03*
X353085Y187485D03*
X355040Y180000D03*
X362017Y183492D03*
X362036Y177155D03*
X358858Y177128D03*
X358848Y174010D03*
X354540Y199000D03*
X358879Y192929D03*
X351320Y194520D03*
X361987Y189747D03*
X358850Y196050D03*
X355090Y195660D03*
X355139Y190099D03*
X351731Y190274D03*
X362500Y286000D03*
X348000Y292500D03*
X361155Y496203D03*
X356555Y513000D03*
X357055Y507000D03*
X356055Y502000D03*
X368307Y133071D03*
X374606Y136221D03*
X368296Y136246D03*
X371456Y136221D03*
X368305Y139401D03*
X371482Y133058D03*
X365133Y129133D03*
X374600Y139390D03*
X377750Y139400D03*
X371458Y142520D03*
X377765Y155146D03*
X374589Y155110D03*
X371455Y148854D03*
X377787Y148812D03*
X368333Y155107D03*
X365140Y155100D03*
X377757Y145670D03*
X368333Y148827D03*
X368329Y151956D03*
X371493Y145667D03*
X368314Y142505D03*
Y145680D03*
X371457Y155080D03*
X377759Y152000D03*
X365146Y151942D03*
X365182Y142532D03*
X374607Y142520D03*
X377757D03*
X365186Y170876D03*
X377732Y167703D03*
X377718Y161417D03*
X371470Y167741D03*
X371489Y161411D03*
X368309Y170830D03*
X368334Y167706D03*
X365158Y164554D03*
X368325Y164585D03*
X368326Y161400D03*
X368271Y158268D03*
X374582Y161404D03*
X374577Y164559D03*
X377750Y170846D03*
X374570Y158267D03*
X365176Y161400D03*
X365186Y177175D03*
X368320Y183460D03*
X377741Y177188D03*
X377731Y180302D03*
X371457Y173978D03*
X365187Y186605D03*
X368308Y177202D03*
X374560Y177210D03*
X371485Y177175D03*
X368336Y189755D03*
X368307Y196062D03*
Y202361D03*
X377755D03*
Y199211D03*
Y196062D03*
Y192912D03*
Y189763D03*
X368307Y205511D03*
Y199211D03*
X368336Y192904D03*
X374606Y189763D03*
Y192912D03*
X374607Y218110D03*
X374606Y211810D03*
X377756D03*
X365158D03*
X371457D03*
X367665Y363430D03*
X368055Y380500D03*
X368555Y385000D03*
Y376500D03*
X371781Y387924D03*
X368555Y389000D03*
X368165Y393402D03*
X370500Y518000D03*
X379500Y963500D03*
X390354Y136221D03*
X380906Y136220D03*
X390355Y139371D03*
X380920Y139370D03*
X387173Y139376D03*
X392240Y129000D03*
X383680Y129030D03*
X396683Y139362D03*
X393510Y139340D03*
X384019Y139371D03*
X384055Y155117D03*
X396653D03*
X380907Y142520D03*
X387206Y145670D03*
X390355Y142520D03*
X393505Y145670D03*
X384093Y151968D03*
X393519Y151990D03*
X384056Y145670D03*
X390355D03*
X396655D03*
X387206Y142520D03*
X384056D03*
X390339Y151990D03*
X396639D03*
X380888Y148799D03*
X396655Y142520D03*
X393505D03*
X384055Y158266D03*
X396653D03*
X390354Y167715D03*
X396653D03*
X384032Y167703D03*
X380944Y161417D03*
X387219Y158290D03*
X387205Y167715D03*
X384041Y170888D03*
X380928Y167701D03*
X393528Y167702D03*
X390392Y186614D03*
X384055Y186613D03*
X396654Y186614D03*
X396653Y174015D03*
Y180314D03*
X387204Y177164D03*
X384032Y174003D03*
X384030Y177120D03*
X393542Y186614D03*
X393490Y174039D03*
X393541Y180315D03*
X384055Y202361D03*
X393503Y205510D03*
X396654Y202362D03*
X396653Y205511D03*
Y199211D03*
X384055Y192912D03*
Y196062D03*
X396653Y192912D03*
X384036Y189747D03*
X393519Y192900D03*
X387209Y192930D03*
X393503Y211809D03*
X380906Y211810D03*
X396654D03*
X396653Y208660D03*
X393503D03*
X390354Y218109D03*
Y221259D03*
X384055Y211810D03*
X393504Y218109D03*
X390354Y224408D03*
X395500Y237000D03*
X389500Y319150D03*
X392589Y317729D03*
X394055Y335000D03*
X391325Y324520D03*
X386755Y326100D03*
X384160Y328812D03*
X391555Y338350D03*
X393061Y346800D03*
X393755Y350500D03*
X390230Y349327D03*
X396055Y338000D03*
X395855Y366890D03*
X392991Y365797D03*
X391628Y358852D03*
X394915Y359725D03*
X387515Y365500D03*
X387265Y384370D03*
X394935Y385150D03*
X382803Y385207D03*
X391215Y384900D03*
X396490Y388597D03*
X388500Y400575D03*
X390543Y391950D03*
X387000Y404275D03*
X396500Y910500D03*
X388750Y951750D03*
X387061Y986061D03*
X389500Y992000D03*
X402950Y133050D03*
X399835Y139375D03*
X412429Y136210D03*
X399783Y136237D03*
X402953Y139370D03*
X402800Y129180D03*
X406103Y139371D03*
X412415Y148794D03*
X399779Y142531D03*
X399804Y145670D03*
X412403Y142520D03*
X406102Y155117D03*
X412402Y155118D03*
X412401Y151967D03*
X399819Y151950D03*
X406125Y148804D03*
X406110Y145660D03*
X402954Y145670D03*
Y142520D03*
X406103D03*
X402938Y151950D03*
X402952Y167715D03*
X409251D03*
X412401Y158267D03*
X406102D03*
X399827Y167702D03*
X406140Y167716D03*
X406127Y161404D03*
X412427D03*
X412426Y167703D03*
X402977Y174003D03*
X402952Y186613D03*
X409251D03*
X409288Y180315D03*
X402952Y180314D03*
X409251Y174015D03*
X399841Y186614D03*
X399840Y180315D03*
X399790Y174039D03*
X406126Y174003D03*
X406139Y180315D03*
X406101Y186613D03*
X412426Y174003D03*
X412439Y186614D03*
X412400Y180314D03*
X412401Y205510D03*
X402952Y192912D03*
X409251D03*
X406128Y192901D03*
X399791Y192938D03*
X412428Y192901D03*
X402953Y211810D03*
X412402D03*
X399803Y218109D03*
Y221259D03*
Y208660D03*
Y211810D03*
X406102D03*
X406099Y214950D03*
X409249Y214965D03*
X412767Y233162D03*
X400000Y237500D03*
X409500Y271500D03*
X404920Y330117D03*
X412794D03*
X404920Y334054D03*
X412794D03*
X408857D03*
X400983D03*
X397983Y333998D03*
X408857Y330117D03*
X400523Y325283D03*
X412815Y349860D03*
X408857Y341928D03*
X412794D03*
X397555Y345146D03*
X398055Y350296D03*
X398555Y339283D03*
X408857Y345865D03*
X404965Y342120D03*
X412794Y337991D03*
X400055Y343146D03*
X408857Y365550D03*
Y357676D03*
X412794Y365550D03*
Y357676D03*
X397117Y364138D03*
X412794Y353739D03*
X404920Y369487D03*
X412794Y361613D03*
X408925Y361680D03*
X400395Y362450D03*
X400885Y354120D03*
X404935Y353840D03*
X412794Y369487D03*
X408857D03*
Y353739D03*
Y385237D03*
Y377363D03*
X412794D03*
Y385237D03*
Y381300D03*
X399923Y372000D03*
X408857Y400985D03*
Y393111D03*
X412794Y400985D03*
Y393111D03*
X408857Y389174D03*
X400983Y400985D03*
X404920Y397048D03*
Y400985D03*
Y389174D03*
X412794Y397048D03*
Y389174D03*
X408857Y397048D03*
X400983D03*
X404920Y393111D03*
X408857Y416733D03*
Y408859D03*
X412794Y416733D03*
Y408859D03*
X400983Y404922D03*
X412794Y412796D03*
X404920Y404922D03*
X408857D03*
Y412796D03*
X412794Y404922D03*
X404920Y416733D03*
X400983D03*
X408857Y424607D03*
X412794D03*
X408857Y420670D03*
X412794D03*
X404555Y430500D03*
X404920Y420670D03*
X406555Y428300D03*
X399555Y438500D03*
X428375Y119735D03*
X418940Y125000D03*
X415552Y136221D03*
X421590Y128500D03*
X418702Y136221D03*
X413540Y128500D03*
X425000Y136220D03*
X428116Y136218D03*
X421851Y136221D03*
X423686Y126215D03*
X415549Y151990D03*
X418702Y142520D03*
X425001D03*
X421851D03*
X415552D03*
X428151D03*
X418700Y148818D03*
X428149D03*
X415551D03*
X424999D03*
X421850D03*
X428149Y164565D03*
Y170865D03*
X421876Y167705D03*
X415575Y167703D03*
X424999Y161416D03*
X428149D03*
X418726Y167703D03*
X428149Y183463D03*
Y177164D03*
X421876Y174005D03*
Y180304D03*
Y186603D03*
X415551Y186614D03*
X415587Y180315D03*
X415551Y174015D03*
X418726Y174003D03*
Y180303D03*
X418701Y186614D03*
X424999Y199211D03*
X428149D03*
X424999Y202361D03*
X428149D03*
X421876Y192902D03*
X428149Y192912D03*
X415551D03*
X424999D03*
X418727Y192902D03*
X418701Y211810D03*
X425001D03*
X428150D03*
X415551D03*
X421850D03*
X428172Y221320D03*
X424979Y218127D03*
X428047Y218049D03*
X415551Y218109D03*
X418729Y218100D03*
X421850Y218109D03*
X418729Y221268D03*
X420500Y234500D03*
X422630Y227232D03*
X426147Y230982D03*
X420714Y225190D03*
X429444Y230192D03*
X419000Y227405D03*
X427965Y318293D03*
X419913Y318051D03*
X417650Y316400D03*
X416482Y319022D03*
X424555Y318000D03*
X420668Y330117D03*
X428542D03*
X420668Y334054D03*
X428542D03*
X424023Y320783D03*
X424605Y334054D03*
Y330117D03*
X416731D03*
X416950Y321783D03*
X416731Y334054D03*
X424605Y345865D03*
X420668Y337991D03*
X428542Y345865D03*
X416615Y349930D03*
X428542Y349802D03*
Y341928D03*
X424605Y337991D03*
X428542D03*
X420668Y341928D03*
X424605Y349802D03*
X420668D03*
X416731Y337991D03*
X420668Y345865D03*
X416731Y341928D03*
X424605D03*
Y369487D03*
Y361613D03*
Y353739D03*
X428542Y361613D03*
Y369487D03*
Y353739D03*
X416731D03*
X420668Y357676D03*
X428542Y365550D03*
X416731Y369487D03*
X420668Y353739D03*
X416731Y365550D03*
X424605D03*
X420668D03*
X416731Y361613D03*
X420668Y369487D03*
X424605Y357676D03*
X420668Y361613D03*
X416555Y357500D03*
X428542Y357676D03*
X424605Y385237D03*
X428542D03*
Y381300D03*
X428500Y377000D03*
X416731Y381300D03*
Y377363D03*
X428445Y373550D03*
X420668Y377363D03*
Y385237D03*
X416731D03*
X424605Y381300D03*
X420668D03*
X428542Y400985D03*
X424605D03*
Y393111D03*
X428542Y397048D03*
X420668Y400985D03*
X416731Y389174D03*
X428555Y393000D03*
X420668Y389174D03*
X416731Y393111D03*
Y397048D03*
X420668Y393111D03*
X424605Y397048D03*
X428542Y389174D03*
X420668Y397048D03*
X416731Y400985D03*
X424605Y389174D03*
Y404922D03*
Y408859D03*
X420668Y404922D03*
X428542Y408859D03*
X420668D03*
X428542Y404922D03*
X428523Y416683D03*
X416731Y416733D03*
Y404922D03*
Y412796D03*
X424605D03*
X423555Y431500D03*
X416731Y420670D03*
Y424607D03*
X419500Y914000D03*
X440000Y5000D03*
X432540Y123000D03*
X435640D03*
X437599Y136221D03*
X434450D03*
X439540Y124500D03*
X431407Y136285D03*
X440931Y129061D03*
X431348Y125911D03*
X442323Y126000D03*
X437945Y127159D03*
X434449Y155118D03*
X431300Y142520D03*
X437599D03*
X437598Y148818D03*
Y155118D03*
X434450Y142520D03*
X440765Y145670D03*
X443928Y148811D03*
X443891Y151999D03*
X443890Y142565D03*
X443909Y145650D03*
X443936Y155118D03*
X431299Y164565D03*
Y170865D03*
X434449Y167716D03*
Y161417D03*
X431299Y161416D03*
X437598Y167716D03*
Y161417D03*
X443899Y161430D03*
X443882Y167737D03*
X443899Y164530D03*
X443871Y158278D03*
X431299Y183463D03*
X434449Y180314D03*
Y174015D03*
X431299Y177164D03*
X434448Y186613D03*
X431299D03*
X437598Y174015D03*
Y180314D03*
Y186614D03*
X443910Y174041D03*
X443879Y180320D03*
X443887Y177138D03*
X440769Y183480D03*
X443919D03*
X434414Y205514D03*
X434449Y199212D03*
Y192913D03*
X437598Y205511D03*
Y199212D03*
Y192913D03*
X443897Y205512D03*
Y192914D03*
X443898Y199212D03*
X443897Y202363D03*
Y196063D03*
X434449Y211810D03*
X437598D03*
X443897Y211811D03*
Y208662D03*
X431336Y218111D03*
X434448Y218109D03*
X437598D03*
X436529Y229500D03*
X434334Y226789D03*
X443113Y226339D03*
X439980Y232126D03*
X441379Y229700D03*
X432307Y224857D03*
X437112Y232239D03*
X445892Y225995D03*
X436500Y241000D03*
X438500Y250000D03*
X431023Y317283D03*
X430513Y320841D03*
X436416Y330117D03*
X444290D03*
X440353D03*
X434448Y320783D03*
X440353Y334054D03*
X432523Y330283D03*
X444555Y334000D03*
X441335Y321000D03*
X436416Y334054D03*
X440353Y349802D03*
X444290D03*
X440353Y341928D03*
X436416Y345865D03*
X432585Y345850D03*
X444290Y341928D03*
X432365Y341880D03*
X444290Y337991D03*
X432605Y337880D03*
X444290Y345865D03*
X440353D03*
X440555Y338000D03*
X440353Y369487D03*
X444290Y365550D03*
X440353Y353739D03*
X444290Y357676D03*
X432479Y369487D03*
Y361613D03*
X444290Y369487D03*
X436416D03*
X440353Y357676D03*
X444290Y353739D03*
X440353Y365550D03*
X436416Y353739D03*
Y361613D03*
X444290Y385237D03*
Y377363D03*
X440353Y381300D03*
X432479Y385237D03*
X436416Y377363D03*
X432479D03*
Y381300D03*
X444290D03*
X440353Y377363D03*
X436416Y381300D03*
X440353Y400985D03*
Y389174D03*
X432479Y400985D03*
Y397048D03*
Y393111D03*
Y389174D03*
X444290Y397048D03*
X440353D03*
X436416D03*
X444290Y400985D03*
X436416D03*
X444290Y389174D03*
X436416D03*
X432479Y408859D03*
Y404922D03*
X436416D03*
Y408859D03*
X444290Y404922D03*
Y408859D03*
X440353D03*
Y404922D03*
X444323Y416883D03*
X436523Y416683D03*
X440353Y412796D03*
X432479D03*
X442535Y426770D03*
X434723Y426283D03*
X460000Y5000D03*
X448669Y126510D03*
X450209Y129230D03*
X447389Y129580D03*
X454676Y137495D03*
X456429Y135000D03*
X457929Y132500D03*
X451679Y148250D03*
X461685Y150386D03*
X455731Y154302D03*
X460300Y141100D03*
X454929Y146500D03*
X453929Y140334D03*
X459069Y151980D03*
X451329Y165570D03*
X453599Y156693D03*
X458429Y185000D03*
X450196Y189764D03*
X454329Y199800D03*
X452929Y203900D03*
X452329Y194300D03*
X447063Y199234D03*
X447047Y189764D03*
X451292Y197637D03*
X456479Y202400D03*
X455929Y192800D03*
X456229Y196700D03*
X453829Y215600D03*
X453729Y219300D03*
X452393Y210236D03*
X458029Y213469D03*
X457798Y217769D03*
X457729Y206800D03*
X448840Y225775D03*
X455429Y227500D03*
X451929Y229800D03*
X456929Y224507D03*
X456103Y330117D03*
X460040D03*
X448227D03*
X452223Y333983D03*
X448227Y334054D03*
X460040D03*
X456103D03*
X460040Y349802D03*
Y341928D03*
X448227Y349802D03*
Y341928D03*
X456103D03*
X460040Y337991D03*
X455825Y349840D03*
X448000Y346000D03*
X456055Y338000D03*
X452055D03*
X452165Y349470D03*
X456103Y365550D03*
Y357676D03*
X460040Y369487D03*
Y361613D03*
X448227Y369487D03*
Y361613D03*
Y353739D03*
X456103Y369487D03*
Y353739D03*
Y361613D03*
X460040Y357676D03*
Y365550D03*
X448227D03*
Y357676D03*
X456103Y385237D03*
Y377363D03*
X460040Y381300D03*
X448227D03*
X460040Y385237D03*
X456103Y381300D03*
X460040Y377363D03*
X448227Y385237D03*
Y377363D03*
X460040Y389174D03*
X448227D03*
X456103Y400985D03*
X460040D03*
X456103Y393111D03*
X460040D03*
Y397048D03*
X448227Y400985D03*
Y393111D03*
X456103Y397048D03*
X448227D03*
X456103Y389174D03*
X456223Y404883D03*
Y408783D03*
X456103Y412796D03*
X460023Y408883D03*
X452123Y416783D03*
X460040Y412796D03*
X448227D03*
X452223Y404883D03*
X448227Y408859D03*
X452223Y408783D03*
X448227Y404922D03*
X450725Y425460D03*
X471480Y105660D03*
X466464Y151000D03*
X466500Y144500D03*
X463969Y147610D03*
X469429Y172500D03*
Y165590D03*
X473131Y169131D03*
X477429Y162500D03*
X469429Y179500D03*
X465679Y192600D03*
X464570Y215750D03*
X467300Y320100D03*
X471851Y322243D03*
Y326180D03*
X463977Y330117D03*
X467914D03*
X463977Y334054D03*
X467914D03*
X475788Y330117D03*
Y349802D03*
Y341928D03*
X467914Y349802D03*
X463977Y341928D03*
X471851Y337991D03*
X467914D03*
X463977D03*
X471851Y349802D03*
X467914Y345865D03*
X475788Y369487D03*
Y361613D03*
Y357676D03*
X467914Y369487D03*
Y361613D03*
Y365550D03*
Y357676D03*
Y353739D03*
X463977Y365550D03*
Y357676D03*
X471851Y361613D03*
Y369487D03*
Y353739D03*
Y357676D03*
X463977Y369487D03*
Y361613D03*
Y385237D03*
X475788Y381300D03*
Y377363D03*
X467914Y385237D03*
Y377363D03*
Y381300D03*
X463977Y377363D03*
X471851D03*
Y381300D03*
X463977D03*
X475788Y400985D03*
Y397048D03*
Y393111D03*
X471851D03*
Y397048D03*
X475788Y389174D03*
X467914Y400985D03*
Y397048D03*
Y393111D03*
Y389174D03*
X463977Y393111D03*
Y397048D03*
Y400985D03*
X471851D03*
Y389174D03*
X463977D03*
Y408859D03*
Y404922D03*
X467914Y408859D03*
Y404922D03*
X471851Y412796D03*
X475788D03*
X471851Y416733D03*
X467914Y412796D03*
X475788Y424607D03*
X485000Y5000D03*
X480500Y181800D03*
X493855Y312700D03*
X488155Y315700D03*
X490455Y319200D03*
X481255Y320000D03*
X483955Y318600D03*
X491536Y334054D03*
X479725Y330117D03*
X479655Y322500D03*
X487500Y333833D03*
X483662Y334054D03*
X487599Y330117D03*
X483662Y326180D03*
X484000Y322000D03*
X487599Y326180D03*
X487155Y321900D03*
X483662Y330117D03*
X491536Y341928D03*
X479725Y337991D03*
X487599D03*
X483662D03*
Y341928D03*
X487599D03*
X483662Y345865D03*
X487599Y349802D03*
X483662D03*
X487599Y345865D03*
X479725Y341928D03*
Y349802D03*
X487603Y369483D03*
X483662Y357676D03*
X487599D03*
X483663Y365463D03*
X483662Y361613D03*
Y353739D03*
X487599D03*
X483683Y369403D03*
X479725Y369487D03*
Y361613D03*
X487643Y361523D03*
X491500Y353500D03*
X491536Y369487D03*
Y361613D03*
X479725Y365550D03*
Y357676D03*
X491536Y385237D03*
Y377363D03*
X479725Y381300D03*
X491536D03*
X479725Y385237D03*
Y377363D03*
X491536Y400985D03*
Y393111D03*
X479725Y397048D03*
Y389174D03*
X491536Y397048D03*
Y389174D03*
X479725Y400985D03*
Y393111D03*
X491536Y416733D03*
Y408859D03*
X487599Y416733D03*
X483662Y408859D03*
X487599Y404922D03*
X479725Y412796D03*
X491536D03*
Y404922D03*
X483662Y412796D03*
Y404922D03*
X479725Y416733D03*
X491536Y420670D03*
Y424607D03*
X483662D03*
X487599D03*
Y420670D03*
X505678Y310921D03*
X506000Y317500D03*
X498855Y311100D03*
X498955Y316900D03*
X505523Y332086D03*
X499410Y322243D03*
X495473Y334054D03*
X511500Y348000D03*
X511455Y338700D03*
X495473Y341928D03*
X505523Y363582D03*
X507955Y356100D03*
X505523Y371456D03*
X503347Y381300D03*
X495473Y385237D03*
Y377363D03*
X503347Y397048D03*
Y389174D03*
X495473Y400985D03*
Y393111D03*
X499410Y416733D03*
Y412796D03*
Y408859D03*
X503347D03*
Y404922D03*
X495473Y416733D03*
Y412796D03*
Y408859D03*
X499410Y420670D03*
Y424607D03*
X503347Y420670D03*
X495473Y424607D03*
Y420670D03*
X515000Y5000D03*
X521700Y114000D03*
X513407Y311502D03*
X513500Y315800D03*
X522345Y311699D03*
X522365Y316365D03*
X521800Y322000D03*
X527667Y322182D03*
X523500Y347500D03*
Y352000D03*
Y342000D03*
X523100Y364300D03*
X526800Y359600D03*
X519500Y365500D03*
X523500Y357500D03*
X538875Y138000D03*
X533441Y211775D03*
X542000Y249000D03*
X528600Y316700D03*
X539300Y317600D03*
X534000Y317500D03*
X539200Y324100D03*
X530000Y342000D03*
X529400Y352800D03*
X530100Y347200D03*
X545000Y5000D03*
X546500Y147500D03*
X559750Y264500D03*
X547500Y360168D03*
X575000Y5000D03*
X568500Y147500D03*
X563250Y262500D03*
X579221Y237250D03*
X580828Y260028D03*
X604500Y205000D03*
Y200500D03*
X603500Y218500D03*
Y214000D03*
X605000Y209500D03*
X594500Y236000D03*
X604500Y227500D03*
Y223000D03*
X599000Y804000D03*
X622500Y696500D03*
X625000Y706000D03*
X632500Y530000D03*
X685000Y5000D03*
X691400Y231100D03*
X695000Y20000D03*
X700000Y60500D03*
X715000Y5000D03*
X725000Y20000D03*
X710100Y182700D03*
X720500Y478750D03*
X723000Y996500D03*
X731498D03*
X739368Y996610D03*
X727558Y996500D03*
X745000Y5000D03*
X755000Y20000D03*
X756000Y180000D03*
X775000Y5000D03*
X785000Y20000D03*
X780000Y250000D03*
X805000Y5000D03*
X815000Y20000D03*
X810000Y980000D03*
X835000Y5000D03*
X840000Y980000D03*
X850000Y20000D03*
X865000Y5000D03*
X862500Y65000D03*
X866112Y85626D03*
X865000Y488500D03*
X870000Y980000D03*
X880000Y20000D03*
X874000Y56000D03*
X873500Y61500D03*
X884500Y323500D03*
X881000Y736500D03*
X895000Y5000D03*
X902000Y63000D03*
X900000Y980000D03*
X910000Y20000D03*
X925000Y5000D03*
X935000Y51500D03*
X937000Y63000D03*
X955000Y5000D03*
X940000Y20000D03*
X945000Y141500D03*
X947500Y153000D03*
X970000Y20000D03*
X959900Y180700D03*
X985000Y5000D03*
X974500Y188500D03*
X975007Y194300D03*
X1000000Y20000D03*
X1002500Y653000D03*
X1001100Y776500D03*
X1015000Y5000D03*
Y477500D03*
X1011500Y667500D03*
X1010000Y980000D03*
X1022000Y492500D03*
X1022500Y637500D03*
X1027504Y853366D03*
X1045000Y5000D03*
Y266600D03*
X1041410Y695394D03*
Y690694D03*
Y699834D03*
X1040000Y980000D03*
X1060000Y20000D03*
X1055000Y214500D03*
X1055500Y360000D03*
X1062940Y629945D03*
X1065978Y664568D03*
X1063056Y681554D03*
X1062700Y672600D03*
X1054080Y680630D03*
X1061696Y761294D03*
X1061356Y753354D03*
X1075000Y5000D03*
X1084500Y223500D03*
X1074000Y660500D03*
X1074500Y665500D03*
X1070000Y980000D03*
X1090000Y20000D03*
X1102000Y250000D03*
X1102500Y264500D03*
X1089500Y405000D03*
X1088000Y461000D03*
X1088400Y647484D03*
X1100000Y980000D03*
X1105000Y5000D03*
Y15000D03*
Y75000D03*
Y105000D03*
Y135000D03*
X1103300Y492000D03*
X1113500Y614250D03*
X1113000Y630500D03*
X1105000D03*
X1114500Y645000D03*
X1118630Y714820D03*
X1110790Y738850D03*
X1116550Y783600D03*
X1119060Y791083D03*
X1132500Y333000D03*
X1126500Y614500D03*
X1132423Y663902D03*
X1135553Y663957D03*
X1132440Y676555D03*
X1129272Y673350D03*
X1129271Y670275D03*
X1126102Y676518D03*
X1122985Y670262D03*
X1122938Y676540D03*
X1132402Y673405D03*
X1132398Y667102D03*
X1129290Y676555D03*
X1126121Y679722D03*
X1132421Y679648D03*
X1132395Y670225D03*
X1126117Y685952D03*
X1129273Y689170D03*
X1126122Y689171D03*
X1129290Y692303D03*
X1126116Y692279D03*
X1132423Y695469D03*
X1132440Y692265D03*
Y686004D03*
X1132434Y682860D03*
X1129278Y682804D03*
X1119265Y683864D03*
X1135551Y685967D03*
X1129289Y686005D03*
X1126157Y695435D03*
X1129238Y704878D03*
X1132440Y701714D03*
X1129270D03*
X1126121Y711218D03*
X1129285Y708056D03*
X1126114Y701703D03*
X1126093Y704874D03*
X1132406Y704904D03*
X1132440Y698564D03*
X1129290D03*
X1126155Y708029D03*
X1132445Y714345D03*
X1129260Y714350D03*
X1135570Y711218D03*
X1126121Y714368D03*
X1132417Y711189D03*
X1129277Y711210D03*
X1128959Y729952D03*
X1126969Y727981D03*
X1132398Y720624D03*
X1132459Y717481D03*
X1127183Y740805D03*
X1126671Y744629D03*
X1126885Y736721D03*
X1123393Y743726D03*
X1124497Y734140D03*
X1124326Y738960D03*
X1126955Y731909D03*
X1124978Y747578D03*
X1130900Y766700D03*
X1124460Y768140D03*
X1125900Y764200D03*
X1129501Y776929D03*
X1134245Y769145D03*
X1127945Y769970D03*
X1121215Y769936D03*
X1120400Y781600D03*
X1126360Y792640D03*
X1127160Y788837D03*
X1129497Y792673D03*
X1130610Y788820D03*
X1134145Y788450D03*
X1132684Y792636D03*
X1124360Y788390D03*
X1132600Y784822D03*
X1120529Y786350D03*
X1123254Y792663D03*
X1131095Y799965D03*
X1124796Y800150D03*
X1135000Y810000D03*
X1134244Y799984D03*
X1121000Y808500D03*
X1127945Y799935D03*
X1121646Y799924D03*
X1123500Y832470D03*
X1135500Y835000D03*
X1130000Y980000D03*
X1144425Y325500D03*
X1143000Y629000D03*
X1138757Y663937D03*
X1151337Y660807D03*
X1151354Y663936D03*
X1148150Y663956D03*
X1141900Y663944D03*
X1148188Y667106D03*
Y670256D03*
X1151282Y667088D03*
X1141600Y673590D03*
X1141868Y680064D03*
X1151337Y670256D03*
X1141954Y676581D03*
X1135589Y673368D03*
X1144983Y667085D03*
X1145020Y670200D03*
X1136150Y676500D03*
X1135685Y679613D03*
X1135598Y667080D03*
X1135595Y670225D03*
X1141868Y670273D03*
X1138708Y667113D03*
X1139245Y675106D03*
X1135589Y682854D03*
Y695415D03*
X1151300Y682854D03*
Y692303D03*
Y689153D03*
Y686004D03*
Y695452D03*
X1148150D03*
Y692303D03*
Y689153D03*
Y686004D03*
Y682854D03*
X1139858Y692074D03*
X1139000Y685667D03*
X1144880Y707720D03*
X1145000Y711200D03*
X1138729Y714360D03*
X1151307Y714306D03*
X1141765Y711030D03*
X1145053Y714327D03*
X1148169Y711219D03*
X1141840Y714339D03*
X1138320Y710066D03*
X1151300Y698602D03*
X1148150D03*
X1135589Y701714D03*
X1151352Y711178D03*
X1140710Y707750D03*
X1138400Y705300D03*
X1136304Y707482D03*
X1151318Y717518D03*
X1148135Y720634D03*
X1138685Y720633D03*
X1141870Y717518D03*
X1148167Y717517D03*
X1138730Y717480D03*
X1141904Y720633D03*
X1150734Y736950D03*
X1149470Y734451D03*
X1137030Y745300D03*
X1146370Y769310D03*
X1142095Y773774D03*
X1151564Y776924D03*
X1146200Y766300D03*
X1142323Y780250D03*
X1138961Y776940D03*
X1145265Y776945D03*
X1151592Y773748D03*
X1150310Y783840D03*
X1142120Y795830D03*
X1145270D03*
X1138970D03*
X1145270Y792670D03*
X1141700Y785113D03*
X1138545Y787952D03*
X1145740Y789140D03*
X1138931Y792658D03*
X1142086Y789513D03*
X1136236Y782142D03*
X1151590Y792660D03*
X1143470Y782805D03*
X1140650Y782496D03*
X1151565Y787951D03*
X1142110Y792660D03*
X1149400Y800000D03*
X1142010Y809500D03*
X1141100Y831600D03*
X1159100Y640800D03*
X1157599Y663956D03*
X1167098Y663932D03*
X1160748Y660807D03*
Y657657D03*
X1160741Y663949D03*
X1163946Y663946D03*
X1157613Y673418D03*
X1167692Y674996D03*
X1160768Y676535D03*
X1154470Y673363D03*
X1152090Y677010D03*
X1154218Y679964D03*
X1154496Y667096D03*
X1163917Y670275D03*
X1160741Y667099D03*
X1163914Y673352D03*
X1167034Y667092D03*
X1157655Y667087D03*
X1160770Y673421D03*
X1163944Y667076D03*
X1154487Y670256D03*
X1160748Y682854D03*
X1157599Y686004D03*
X1154449D03*
Y682854D03*
Y689153D03*
X1160748Y695452D03*
X1157599D03*
Y692303D03*
X1154449Y695452D03*
Y692303D03*
X1163898Y695452D03*
X1160748Y692303D03*
X1163898D03*
X1157599Y689153D03*
X1160748D03*
X1163898D03*
X1160748Y686004D03*
X1163898D03*
X1157670Y707960D03*
X1167048Y714312D03*
X1163968Y708000D03*
X1154434Y714335D03*
X1157581Y714331D03*
X1163905Y711206D03*
X1157636Y711200D03*
X1163898Y698602D03*
X1160748D03*
X1157599D03*
X1154449D03*
X1167103Y711107D03*
X1167000Y727500D03*
X1157637Y717463D03*
X1157643Y720642D03*
X1152248Y730404D03*
X1154430Y717481D03*
X1152400Y727600D03*
X1167049Y717501D03*
X1167048Y720612D03*
X1163898Y717462D03*
Y720612D03*
X1157112Y731702D03*
X1164200Y744500D03*
X1157000Y734500D03*
X1166100Y731500D03*
X1152023Y733299D03*
X1163830Y747899D03*
X1158100Y769700D03*
X1162450Y769190D03*
X1167002Y767508D03*
X1167326Y776936D03*
X1167320Y770290D03*
X1157871Y773728D03*
X1161051Y792660D03*
X1164196Y795814D03*
X1153219Y781303D03*
X1161545Y788844D03*
X1162693Y780865D03*
X1158092Y787715D03*
X1154712Y792690D03*
X1165492Y780957D03*
X1154200Y788900D03*
X1154700Y795790D03*
X1161022Y785693D03*
X1165063Y787500D03*
X1167410Y785530D03*
X1167330Y795830D03*
X1163605Y783513D03*
X1167277Y792658D03*
X1157866Y795844D03*
X1154800Y799000D03*
X1165300Y809610D03*
X1160300D03*
X1154300D03*
X1155390Y818000D03*
X1157990Y827000D03*
X1155000Y980000D03*
X1173332Y663938D03*
X1176506Y663916D03*
X1176525Y679676D03*
X1170181Y670240D03*
X1176503Y670218D03*
X1182803Y670234D03*
X1176534Y673368D03*
X1179653Y670234D03*
X1173309Y673406D03*
X1179662Y673421D03*
X1176534Y676555D03*
X1179667Y679655D03*
X1182831Y679666D03*
X1182815Y676573D03*
X1170192Y667100D03*
X1176526Y667092D03*
X1173403Y670237D03*
X1173349Y667099D03*
X1182785Y685977D03*
X1176520Y685970D03*
X1179663Y685959D03*
X1173365Y695397D03*
X1169800Y682200D03*
X1173392Y685974D03*
X1173389Y689121D03*
X1176482Y682840D03*
X1176529Y692276D03*
X1179685Y692292D03*
X1176496Y695415D03*
X1179664Y695466D03*
X1182796Y695415D03*
X1179678Y689111D03*
X1182817Y689155D03*
X1173384Y692265D03*
X1182815Y701696D03*
X1182796Y708013D03*
X1182813Y698619D03*
X1176496Y698564D03*
X1179671Y698565D03*
X1170248Y714330D03*
X1173350Y698590D03*
X1179703Y714331D03*
X1173347Y714350D03*
X1176503Y714342D03*
X1176515Y704845D03*
X1179676Y711207D03*
X1179660Y704850D03*
X1171200Y706170D03*
X1179660Y708050D03*
X1176515Y708045D03*
X1173015Y708329D03*
X1176515Y711144D03*
X1173262Y711119D03*
X1182802Y714356D03*
X1169282Y729708D03*
X1173400Y717480D03*
X1176499Y720609D03*
X1170199Y717501D03*
X1173348Y720613D03*
X1176489Y717469D03*
X1171500Y733725D03*
X1175000Y734870D03*
X1171108Y777368D03*
X1170950Y795960D03*
X1170911Y784912D03*
X1170718Y782118D03*
X1170300Y809610D03*
X1185965Y676573D03*
X1190500Y674207D03*
X1185945Y695415D03*
X1190000Y699500D03*
X1196000Y710500D03*
X1190000Y705500D03*
X1199500Y743500D03*
X1185000Y980000D03*
X1211500Y5500D03*
Y35500D03*
Y65500D03*
Y85500D03*
Y107500D03*
Y137500D03*
X1201250Y627000D03*
X1203500Y698520D03*
X1215000Y980000D03*
X1218040Y719850D03*
X1235500Y5000D03*
X1249773Y551500D03*
X1249000Y723250D03*
X1245000Y980000D03*
X1258562Y672438D03*
X1259000Y699500D03*
X1257500Y710500D03*
X1259500Y724000D03*
X1268000Y5000D03*
X1279600Y694800D03*
X1276000Y694000D03*
X1272700Y694900D03*
X1277000Y712500D03*
X1272500D03*
X1275000Y732000D03*
Y980000D03*
X1287962Y710490D03*
X1289500Y716500D03*
X1292500Y730478D03*
X1307500Y5000D03*
X1305000Y596500D03*
X1306423Y608164D03*
X1305217Y612412D03*
X1305435Y603918D03*
X1306443Y618985D03*
X1307150Y691500D03*
X1307000Y729100D03*
X1310500Y737500D03*
X1307000Y732500D03*
X1300491Y732991D03*
X1300000Y980000D03*
X1319400Y522100D03*
X1318700Y533500D03*
X1322900Y524600D03*
X1322400Y533100D03*
X1318000Y696500D03*
X1319000Y708000D03*
X1330000Y980000D03*
X1337500Y5000D03*
X1354900Y522600D03*
X1351900Y524600D03*
X1352400Y533600D03*
X1355900Y536600D03*
X1360000Y980000D03*
X1381415Y581195D03*
X1379600Y584200D03*
X1378800Y594900D03*
X1380925Y598315D03*
X1377800Y603800D03*
X1378082Y614266D03*
X1381637Y611225D03*
X1381578Y607117D03*
X1377996Y610847D03*
X1380925Y602035D03*
X1377996Y607382D03*
X1394122Y5878D03*
X1385135Y581195D03*
X1387200Y584100D03*
X1384400Y598300D03*
Y601900D03*
X1784450Y862250D03*
G54D17*
X121890Y269528D03*
X131890D03*
X141890D03*
X1346396Y21656D03*
X1338526D03*
X1346396Y29526D03*
X1338526D03*
X1362146Y21656D03*
X1354271D03*
X1362146Y29526D03*
X1354271D03*
X1377896Y21656D03*
X1370021D03*
X1377896Y29526D03*
X1370021D03*
X1385766Y21656D03*
Y29526D03*
X1784450Y693650D03*
G54D35*
X1224016Y386221D03*
X1784450Y384550D03*
G54D26*
X590315Y9134D03*
Y19134D03*
X649527Y9134D03*
Y19134D03*
Y29134D03*
X1784450Y525050D03*
G54D36*
X1258504Y329331D03*
Y368701D03*
X1272677Y349016D03*
X1784450Y581250D03*
G54D27*
X585315Y44134D03*
X654527D03*
X1784450Y496950D03*
G54D18*
X153937Y238898D03*
Y246772D03*
Y260551D03*
X224015Y234961D03*
Y246772D03*
Y260551D03*
X1784450Y721750D03*
G54D28*
X600925Y44134D03*
X638917D03*
X1784450Y131650D03*
G54D37*
X1272441Y7087D03*
X1299213D03*
X1784450Y356450D03*
G54D19*
X180118Y729409D03*
Y739409D03*
X200118Y729409D03*
X190118D03*
X200118Y739409D03*
X190118D03*
X210118Y729409D03*
Y739409D03*
X230118Y729409D03*
X220118D03*
X230118Y739409D03*
X220118D03*
X250118Y729409D03*
X240118D03*
X250118Y739409D03*
X240118D03*
X260118Y729409D03*
Y739409D03*
X270118Y729409D03*
Y739409D03*
X1784450Y553150D03*
G54D29*
X599941Y70118D03*
X607933D03*
X595905Y80118D03*
X603897D03*
X611889D03*
X615925Y70118D03*
X623917D03*
X627953Y80118D03*
X631909Y70118D03*
X639901D03*
X635945Y80118D03*
X643937D03*
X1784450Y665550D03*
G54D38*
X1379862Y108465D03*
Y119095D03*
X1784450Y412650D03*
G54D39*
G01X-245081Y-422119D02*
G02I-12000J0D01*
G01X-250231D02*
G02I-6850J0D01*
G01X-241081D02*
X-273081D01*
G01X-257081Y-438119D02*
Y-406119D01*
G01X-241081Y-438119D02*
Y-518119D01*
G01D02*
X1034819D01*
G01X-241081Y-473619D02*
X1034819D01*
G01X-241081Y-438119D02*
X1034819D01*
G01X247319D02*
Y-518119D01*
G01X384819Y-438119D02*
Y-518119D01*
G01X499819Y-438119D02*
Y-518119D01*
G01X667319Y-438119D02*
Y-518119D01*
G01X837319Y-438119D02*
Y-518119D01*
G01X1034819Y-438119D02*
Y-518119D01*
G01X1066819Y-422119D02*
X1034819D01*
G01X1050819Y-438119D02*
Y-406119D01*
G01X1062819Y-422119D02*
G02I-12000J0D01*
G01X1057669D02*
G02I-6850J0D01*
M02*
